FILE_TYPE = MACRO_DRAWING;
SET COLOR_WIRE YELLOW;
SET COLOR_PROP ORANGE;
SET COLOR_DOT WHITE;
SET COLOR_ARC YELLOW;
SET COLOR_BODY GREEN;
SET COLOR_NOTE PURPLE;
SET PROP_DISPLAY VALUE;
SET PAGE_NUMBER P147;
FORCEADD OFFPAGE..2
R 2
(-675 3450);
FORCEPROP 2 LAST $XR1 227 
J 0
(-1050 3450);
DISPLAY 0.638298 (-1050 3450);
PAINT MONO (-1050 3450);
FORCEPROP 2 LAST $XR0 142 
J 0
(-930 3450);
DISPLAY 0.638298 (-930 3450);
PAINT MONO (-930 3450);
FORCEPROP 1 LAST OFFPAGE TRUE
J 2
(-1000 3325);
DISPLAY 0.872340 (-1000 3325);
PAINT AQUA (-1000 3325);
DISPLAY INVISIBLE (-1000 3325);
FORCEPROP 1 LAST COMMENT_BODY TRUE
J 2
(-630 3355);
DISPLAY 0.872340 (-630 3355);
PAINT GREEN (-630 3355);
DISPLAY INVISIBLE (-630 3355);
FORCEPROP 2 LAST CDS_LIB standard
J 0
(-675 3450);
DISPLAY INVISIBLE (-675 3450);
FORCEPROP 2 LAST PATH I1
J 0
(-925 3500);
DISPLAY 1.021277 (-925 3500);
DISPLAY INVISIBLE (-925 3500);
FORCEADD Q_RES..1
(550 4275);
FORCEPROP 1 LAST PART_NUMBER CS11002FB07
J 0
(450 4225);
DISPLAY 0.404255 (450 4225);
DISPLAY INVISIBLE (450 4225);
FORCEPROP 1 LAST TOLERANCE 1%
J 0
(1125 4050);
DISPLAY 0.510638 (1125 4050);
FORCEPROP 1 LAST VALUE 100
J 2
(725 4275);
DISPLAY 0.510638 (725 4275);
FORCEPROP 1 LAST MATERIAL EMPTY
J 0
(625 4250);
DISPLAY 0.510638 (625 4250);
PAINT RED (625 4250);
FORCEPROP 1 LAST WATTAGE 1/16W
J 2
(550 4200);
DISPLAY 0.404255 (550 4200);
FORCEPROP 1 LAST PACK_TYPE 0402LF
J 0
(575 4200);
DISPLAY 0.404255 (575 4200);
FORCEPROP 1 LAST $LOCATION R2656
J 0
(325 4275);
DISPLAY 0.638298 (325 4275);
FORCEPROP 1 LASTPIN (450 4275) $PN 1
J 0
(462 4287);
DISPLAY 0.787234 (462 4287);
FORCEPROP 1 LASTPIN (650 4275) $PN 2
J 0
(612 4287);
DISPLAY 0.787234 (612 4287);
FORCEPROP 2 LAST CDS_LIB pure_quanta
J 0
(550 4275);
PAINT MONO (550 4275);
DISPLAY INVISIBLE (550 4275);
FORCEPROP 1 LAST PATH I11
J 0
(500 4425);
DISPLAY 0.978723 (500 4425);
PAINT WHITE (500 4425);
DISPLAY INVISIBLE (500 4425);
FORCEPROP 2 LAST CDS_LOCATION R2656
J 0
(500 4475);
DISPLAY 1.021277 (500 4475);
DISPLAY INVISIBLE (500 4475);
FORCEPROP 2 LAST $SEC 1
J 0
(500 4475);
DISPLAY 0.680851 (500 4475);
PAINT MONO (500 4475);
DISPLAY INVISIBLE (500 4475);
FORCEPROP 2 LAST CDS_SEC 1
J 0
(500 4475);
DISPLAY 1.021277 (500 4475);
DISPLAY INVISIBLE (500 4475);
FORCEADD UNIVERSAL_GND..1
(1575 3025);
FORCEPROP 3 LASTPIN (1575 3075) SIG_NAME GND\g
J 0
(1585 3085);
DISPLAY 0.659574 (1585 3085);
PAINT MONO (1585 3085);
DISPLAY INVISIBLE (1585 3085);
FORCEPROP 1 LAST HDL_POWER GND
J 1
(1600 2950);
DISPLAY 0.872340 (1600 2950);
PAINT GREEN (1600 2950);
DISPLAY INVISIBLE (1600 2950);
FORCEPROP 2 LAST CDS_LIB logical_power
J 0
(1575 3025);
DISPLAY INVISIBLE (1575 3025);
FORCEPROP 1 LAST PATH I13
J 0
(1650 3025);
DISPLAY 0.872340 (1650 3025);
PAINT AQUA (1650 3025);
DISPLAY INVISIBLE (1650 3025);
FORCEADD OFFPAGE..2
(-3275 8500);
FORCEPROP 2 LAST $XR1 227 
J 0
(-2966 8500);
DISPLAY 0.638298 (-2966 8500);
PAINT MONO (-2966 8500);
FORCEPROP 2 LAST $XR0 215 
J 0
(-3086 8500);
DISPLAY 0.638298 (-3086 8500);
PAINT MONO (-3086 8500);
FORCEPROP 2 LAST PATH I14
J 0
(-2950 8550);
DISPLAY 1.021277 (-2950 8550);
DISPLAY INVISIBLE (-2950 8550);
FORCEPROP 1 LAST OFFPAGE TRUE
J 0
(-2950 8375);
DISPLAY 0.872340 (-2950 8375);
PAINT AQUA (-2950 8375);
DISPLAY INVISIBLE (-2950 8375);
FORCEPROP 1 LAST COMMENT_BODY TRUE
J 0
(-3320 8405);
DISPLAY 0.872340 (-3320 8405);
PAINT GREEN (-3320 8405);
DISPLAY INVISIBLE (-3320 8405);
FORCEPROP 2 LAST CDS_LIB standard
J 0
(-3275 8500);
DISPLAY INVISIBLE (-3275 8500);
FORCEADD Q_CAP..1
(-3625 8200);
FORCEPROP 1 LAST PART_NUMBER TMP_QCH21006JB10
J 0
(-3575 8050);
DISPLAY 0.638298 (-3575 8050);
DISPLAY INVISIBLE (-3575 8050);
FORCEPROP 1 LAST VOLTAGE 50V
J 0
(-3575 8200);
DISPLAY 0.638298 (-3575 8200);
FORCEPROP 1 LAST PACK_TYPE 0402
J 0
(-3575 8000);
DISPLAY 0.638298 (-3575 8000);
FORCEPROP 1 LAST VALUE 1000PF
J 0
(-3575 8250);
DISPLAY 0.638298 (-3575 8250);
FORCEPROP 1 LAST TOLERANCE 5%
J 0
(-3575 8150);
DISPLAY 0.638298 (-3575 8150);
FORCEPROP 1 LAST MATERIAL EMPTY
J 0
(-3575 8100);
DISPLAY 0.638298 (-3575 8100);
PAINT RED (-3575 8100);
FORCEPROP 1 LAST $LOCATION C2372
J 0
(-3575 8300);
DISPLAY 0.978723 (-3575 8300);
FORCEPROP 1 LASTPIN (-3625 8300) $PN 1
J 0
(-3615 8280);
DISPLAY 0.787234 (-3615 8280);
PAINT MONO (-3615 8280);
FORCEPROP 1 LASTPIN (-3625 8100) $PN 2
J 0
(-3615 8080);
DISPLAY 0.787234 (-3615 8080);
PAINT MONO (-3615 8080);
FORCEPROP 1 LAST PATH I15
J 0
(-3575 8350);
DISPLAY 0.978723 (-3575 8350);
PAINT WHITE (-3575 8350);
DISPLAY INVISIBLE (-3575 8350);
FORCEPROP 2 LAST CDS_LIB pure_quanta
J 0
(-3625 8200);
DISPLAY INVISIBLE (-3625 8200);
FORCEPROP 0 LAST CDS_LOCATION C2372
J 0
(-3575 8350);
DISPLAY 1.021277 (-3575 8350);
DISPLAY INVISIBLE (-3575 8350);
FORCEPROP 0 LAST $SEC 1
J 0
(-3575 8350);
DISPLAY 0.680851 (-3575 8350);
PAINT MONO (-3575 8350);
DISPLAY INVISIBLE (-3575 8350);
FORCEPROP 0 LAST CDS_SEC 1
J 0
(-3575 8350);
DISPLAY 1.021277 (-3575 8350);
DISPLAY INVISIBLE (-3575 8350);
FORCEADD UNIVERSAL_GND..1
(-3625 8000);
FORCEPROP 3 LASTPIN (-3625 8050) SIG_NAME GND\g
J 0
(-3615 8060);
DISPLAY 0.659574 (-3615 8060);
PAINT MONO (-3615 8060);
DISPLAY INVISIBLE (-3615 8060);
FORCEPROP 1 LAST PATH I16
J 0
(-3550 8000);
DISPLAY 0.872340 (-3550 8000);
PAINT AQUA (-3550 8000);
DISPLAY INVISIBLE (-3550 8000);
FORCEPROP 1 LAST HDL_POWER GND
J 1
(-3600 7925);
DISPLAY 0.872340 (-3600 7925);
PAINT GREEN (-3600 7925);
DISPLAY INVISIBLE (-3600 7925);
FORCEPROP 2 LAST CDS_LIB logical_power
J 0
(-3625 8000);
DISPLAY INVISIBLE (-3625 8000);
FORCEADD UNIVERSAL_POWER..1
(-4400 8900);
FORCEPROP 3 LASTPIN (-4400 8850) SIG_NAME P3V3_AUX\g
J 0
(-4390 8860);
DISPLAY 0.659574 (-4390 8860);
PAINT MONO (-4390 8860);
DISPLAY INVISIBLE (-4390 8860);
FORCEPROP 1 LAST HDL_POWER P3V3_AUX
J 1
(-4400 8950);
DISPLAY 0.872340 (-4400 8950);
PAINT GREEN (-4400 8950);
FORCEPROP 1 LAST PATH I17
J 0
(-4350 8925);
DISPLAY 0.872340 (-4350 8925);
PAINT AQUA (-4350 8925);
DISPLAY INVISIBLE (-4350 8925);
FORCEPROP 2 LAST CDS_LIB logical_power
J 0
(-4400 8900);
PAINT MONO (-4400 8900);
DISPLAY INVISIBLE (-4400 8900);
FORCEADD Q_RES..2
(-4400 8675);
FORCEPROP 1 LAST PART_NUMBER CS24702JB10
J 0
(-4360 8500);
DISPLAY 0.638298 (-4360 8500);
DISPLAY INVISIBLE (-4360 8500);
FORCEPROP 1 LAST TOLERANCE 5%
J 0
(-4355 8700);
DISPLAY 0.638298 (-4355 8700);
FORCEPROP 1 LAST MATERIAL CHIP
J 0
(-4360 8600);
DISPLAY 0.638298 (-4360 8600);
FORCEPROP 1 LAST PACK_TYPE 0402LF
J 0
(-4360 8550);
DISPLAY 0.638298 (-4360 8550);
FORCEPROP 1 LAST WATTAGE 1/16W
J 0
(-4360 8650);
DISPLAY 0.638298 (-4360 8650);
FORCEPROP 1 LAST VALUE 4.7K
J 0
(-4355 8750);
DISPLAY 0.638298 (-4355 8750);
FORCEPROP 1 LAST $LOCATION R4726
J 0
(-4355 8800);
DISPLAY 0.638298 (-4355 8800);
FORCEPROP 1 LASTPIN (-4400 8775) $PN 1
J 0
(-4395 8737);
DISPLAY 0.787234 (-4395 8737);
FORCEPROP 1 LASTPIN (-4400 8575) $PN 2
J 0
(-4395 8585);
DISPLAY 0.787234 (-4395 8585);
FORCEPROP 1 LAST PATH I18
J 0
(-4350 8850);
DISPLAY 0.978723 (-4350 8850);
PAINT WHITE (-4350 8850);
DISPLAY INVISIBLE (-4350 8850);
FORCEPROP 2 LAST CDS_LIB pure_quanta
J 0
(-4400 8675);
PAINT MONO (-4400 8675);
DISPLAY INVISIBLE (-4400 8675);
FORCEPROP 2 LAST CDS_LOCATION R4726
J 0
(-4350 8900);
DISPLAY 1.021277 (-4350 8900);
DISPLAY INVISIBLE (-4350 8900);
FORCEPROP 2 LAST $SEC 1
J 0
(-4350 8900);
DISPLAY 0.680851 (-4350 8900);
PAINT MONO (-4350 8900);
DISPLAY INVISIBLE (-4350 8900);
FORCEPROP 2 LAST CDS_SEC 1
J 0
(-4350 8900);
DISPLAY 1.021277 (-4350 8900);
DISPLAY INVISIBLE (-4350 8900);
FORCEADD UNIVERSAL_GND..1
(-4400 7875);
FORCEPROP 3 LASTPIN (-4400 7925) SIG_NAME GND\g
J 0
(-4390 7935);
DISPLAY 0.659574 (-4390 7935);
PAINT MONO (-4390 7935);
DISPLAY INVISIBLE (-4390 7935);
FORCEPROP 1 LAST PATH I19
J 0
(-4325 7875);
DISPLAY 0.872340 (-4325 7875);
PAINT AQUA (-4325 7875);
DISPLAY INVISIBLE (-4325 7875);
FORCEPROP 1 LAST HDL_POWER GND
J 1
(-4375 7800);
DISPLAY 0.872340 (-4375 7800);
PAINT GREEN (-4375 7800);
DISPLAY INVISIBLE (-4375 7800);
FORCEPROP 2 LAST CDS_LIB logical_power
J 0
(-4400 7875);
DISPLAY INVISIBLE (-4400 7875);
FORCEADD OFFPAGE..2
R 2
(-675 3650);
FORCEPROP 2 LAST $XR1 227 
J 0
(-1050 3650);
DISPLAY 0.638298 (-1050 3650);
PAINT MONO (-1050 3650);
FORCEPROP 2 LAST $XR0 142 
J 0
(-930 3650);
DISPLAY 0.638298 (-930 3650);
PAINT MONO (-930 3650);
FORCEPROP 2 LAST CDS_LIB standard
J 0
(-675 3650);
DISPLAY INVISIBLE (-675 3650);
FORCEPROP 1 LAST COMMENT_BODY TRUE
J 2
(-630 3555);
DISPLAY 0.872340 (-630 3555);
PAINT GREEN (-630 3555);
DISPLAY INVISIBLE (-630 3555);
FORCEPROP 1 LAST OFFPAGE TRUE
J 2
(-1000 3525);
DISPLAY 0.872340 (-1000 3525);
PAINT AQUA (-1000 3525);
DISPLAY INVISIBLE (-1000 3525);
FORCEPROP 2 LAST PATH I2
J 0
(-925 3700);
DISPLAY 1.021277 (-925 3700);
DISPLAY INVISIBLE (-925 3700);
FORCEADD MOSFET_NCH_DUAL..2
(-4450 8250);
FORCEPROP 1 LAST PART_NUMBER BAM138K0003
J 0
(-4299 8156);
DISPLAY 0.723404 (-4299 8156);
PAINT GREEN (-4299 8156);
DISPLAY INVISIBLE (-4299 8156);
FORCEPROP 1 LAST MATERIAL IC
J 0
(-4299 8101);
DISPLAY 0.723404 (-4299 8101);
PAINT GREEN (-4299 8101);
FORCEPROP 2 LAST VALUE PJT138K
J 0
(-4275 8275);
DISPLAY 1.021277 (-4275 8275);
FORCEPROP 2 LAST PART_TYPE SMLF
J 0
(-4275 8325);
DISPLAY 1.021277 (-4275 8325);
FORCEPROP 1 LAST LOCATION Q151
J 0
(-4299 8226);
DISPLAY 0.723404 (-4299 8226);
PAINT GREEN (-4299 8226);
FORCEPROP 0 LASTPIN (-4400 8450) $PN 3
R 1
J 0
(-4410 8460);
DISPLAY 0.680851 (-4410 8460);
PAINT MONO (-4410 8460);
FORCEPROP 0 LASTPIN (-4650 8200) $PN 5
J 2
(-4660 8210);
DISPLAY 0.680851 (-4660 8210);
PAINT MONO (-4660 8210);
FORCEPROP 0 LASTPIN (-4400 8050) $PN 4
R 1
J 2
(-4410 8040);
DISPLAY 0.680851 (-4410 8040);
PAINT MONO (-4410 8040);
FORCEPROP 1 LAST PATH I20
J 0
(-4300 8100);
DISPLAY 0.723404 (-4300 8100);
PAINT GREEN (-4300 8100);
DISPLAY INVISIBLE (-4300 8100);
FORCEPROP 2 LAST CDS_LIB pure_quanta
J 0
(-4450 8250);
DISPLAY INVISIBLE (-4450 8250);
FORCEPROP 1 LAST NEEDS_NO_SIZE TRUE
J 0
(-4300 8141);
DISPLAY 0.468085 (-4300 8141);
PAINT GREEN (-4300 8141);
DISPLAY INVISIBLE (-4300 8141);
FORCEPROP 1 LAST CDS_LMAN_SYM_OUTLINE -150,150,150,-150
J 0
(-4450 8250);
DISPLAY 0.468085 (-4450 8250);
PAINT GREEN (-4450 8250);
DISPLAY INVISIBLE (-4450 8250);
FORCEPROP 0 LAST $SEC 2
J 0
(-4275 8375);
DISPLAY 0.680851 (-4275 8375);
PAINT MONO (-4275 8375);
DISPLAY INVISIBLE (-4275 8375);
FORCEPROP 0 LAST CDS_SEC 2
J 0
(-4275 8375);
DISPLAY 1.021277 (-4275 8375);
DISPLAY INVISIBLE (-4275 8375);
FORCEADD OFFPAGE..2
(-3150 6975);
FORCEPROP 2 LAST $XR0 227 
J 0
(-2961 6975);
DISPLAY 0.638298 (-2961 6975);
PAINT MONO (-2961 6975);
FORCEPROP 1 LAST OFFPAGE TRUE
J 0
(-2825 6850);
DISPLAY 0.872340 (-2825 6850);
PAINT AQUA (-2825 6850);
DISPLAY INVISIBLE (-2825 6850);
FORCEPROP 1 LAST COMMENT_BODY TRUE
J 0
(-3195 6880);
DISPLAY 0.872340 (-3195 6880);
PAINT GREEN (-3195 6880);
DISPLAY INVISIBLE (-3195 6880);
FORCEPROP 2 LAST CDS_LIB standard
J 0
(-3150 6975);
DISPLAY INVISIBLE (-3150 6975);
FORCEPROP 2 LAST PATH I21
J 0
(-2950 7025);
DISPLAY 1.021277 (-2950 7025);
DISPLAY INVISIBLE (-2950 7025);
FORCEADD Q_CAP..1
(-3500 6675);
FORCEPROP 1 LAST PART_NUMBER TMP_QCH21006JB10
J 0
(-3450 6525);
DISPLAY 0.638298 (-3450 6525);
DISPLAY INVISIBLE (-3450 6525);
FORCEPROP 1 LAST VOLTAGE 50V
J 0
(-3450 6675);
DISPLAY 0.638298 (-3450 6675);
FORCEPROP 1 LAST PACK_TYPE 0402
J 0
(-3450 6475);
DISPLAY 0.638298 (-3450 6475);
FORCEPROP 1 LAST TOLERANCE 5%
J 0
(-3450 6625);
DISPLAY 0.638298 (-3450 6625);
FORCEPROP 1 LAST MATERIAL EMPTY
J 0
(-3450 6575);
DISPLAY 0.638298 (-3450 6575);
PAINT RED (-3450 6575);
FORCEPROP 1 LAST VALUE 1000PF
J 0
(-3450 6725);
DISPLAY 0.638298 (-3450 6725);
FORCEPROP 1 LAST $LOCATION C2373
J 0
(-3450 6775);
DISPLAY 0.978723 (-3450 6775);
FORCEPROP 1 LASTPIN (-3500 6775) $PN 1
J 0
(-3490 6755);
DISPLAY 0.787234 (-3490 6755);
PAINT MONO (-3490 6755);
FORCEPROP 1 LASTPIN (-3500 6575) $PN 2
J 0
(-3490 6555);
DISPLAY 0.787234 (-3490 6555);
PAINT MONO (-3490 6555);
FORCEPROP 2 LAST CDS_LIB pure_quanta
J 0
(-3500 6675);
DISPLAY INVISIBLE (-3500 6675);
FORCEPROP 1 LAST PATH I22
J 0
(-3450 6825);
DISPLAY 0.978723 (-3450 6825);
PAINT WHITE (-3450 6825);
DISPLAY INVISIBLE (-3450 6825);
FORCEPROP 0 LAST CDS_LOCATION C2373
J 0
(-3450 6825);
DISPLAY 1.021277 (-3450 6825);
DISPLAY INVISIBLE (-3450 6825);
FORCEPROP 0 LAST $SEC 1
J 0
(-3450 6825);
DISPLAY 0.680851 (-3450 6825);
PAINT MONO (-3450 6825);
DISPLAY INVISIBLE (-3450 6825);
FORCEPROP 0 LAST CDS_SEC 1
J 0
(-3450 6825);
DISPLAY 1.021277 (-3450 6825);
DISPLAY INVISIBLE (-3450 6825);
FORCEADD UNIVERSAL_GND..1
(-3500 6475);
FORCEPROP 3 LASTPIN (-3500 6525) SIG_NAME GND\g
J 0
(-3490 6535);
DISPLAY 0.659574 (-3490 6535);
PAINT MONO (-3490 6535);
DISPLAY INVISIBLE (-3490 6535);
FORCEPROP 1 LAST HDL_POWER GND
J 1
(-3475 6400);
DISPLAY 0.872340 (-3475 6400);
PAINT GREEN (-3475 6400);
DISPLAY INVISIBLE (-3475 6400);
FORCEPROP 2 LAST CDS_LIB logical_power
J 0
(-3500 6475);
DISPLAY INVISIBLE (-3500 6475);
FORCEPROP 1 LAST PATH I23
J 0
(-3425 6475);
DISPLAY 0.872340 (-3425 6475);
PAINT AQUA (-3425 6475);
DISPLAY INVISIBLE (-3425 6475);
FORCEADD UNIVERSAL_POWER..1
(-4275 7375);
FORCEPROP 3 LASTPIN (-4275 7325) SIG_NAME P3V3_AUX\g
J 0
(-4265 7335);
DISPLAY 0.659574 (-4265 7335);
PAINT MONO (-4265 7335);
DISPLAY INVISIBLE (-4265 7335);
FORCEPROP 1 LAST HDL_POWER P3V3_AUX
J 1
(-4275 7425);
DISPLAY 0.872340 (-4275 7425);
PAINT GREEN (-4275 7425);
FORCEPROP 2 LAST CDS_LIB logical_power
J 0
(-4275 7375);
PAINT MONO (-4275 7375);
DISPLAY INVISIBLE (-4275 7375);
FORCEPROP 1 LAST PATH I24
J 0
(-4225 7400);
DISPLAY 0.872340 (-4225 7400);
PAINT AQUA (-4225 7400);
DISPLAY INVISIBLE (-4225 7400);
FORCEADD Q_RES..2
(-4275 7150);
FORCEPROP 1 LAST PART_NUMBER CS24702JB10
J 0
(-4235 6975);
DISPLAY 0.638298 (-4235 6975);
DISPLAY INVISIBLE (-4235 6975);
FORCEPROP 1 LAST TOLERANCE 5%
J 0
(-4230 7175);
DISPLAY 0.638298 (-4230 7175);
FORCEPROP 1 LAST MATERIAL CHIP
J 0
(-4235 7075);
DISPLAY 0.638298 (-4235 7075);
FORCEPROP 1 LAST PACK_TYPE 0402LF
J 0
(-4235 7025);
DISPLAY 0.638298 (-4235 7025);
FORCEPROP 1 LAST WATTAGE 1/16W
J 0
(-4235 7125);
DISPLAY 0.638298 (-4235 7125);
FORCEPROP 1 LAST VALUE 4.7K
J 0
(-4230 7225);
DISPLAY 0.638298 (-4230 7225);
FORCEPROP 1 LAST $LOCATION R4733
J 0
(-4230 7275);
DISPLAY 0.638298 (-4230 7275);
FORCEPROP 1 LASTPIN (-4275 7250) $PN 1
J 0
(-4270 7212);
DISPLAY 0.787234 (-4270 7212);
FORCEPROP 1 LASTPIN (-4275 7050) $PN 2
J 0
(-4270 7060);
DISPLAY 0.787234 (-4270 7060);
FORCEPROP 2 LAST CDS_LIB pure_quanta
J 0
(-4275 7150);
PAINT MONO (-4275 7150);
DISPLAY INVISIBLE (-4275 7150);
FORCEPROP 1 LAST PATH I25
J 0
(-4225 7325);
DISPLAY 0.978723 (-4225 7325);
PAINT WHITE (-4225 7325);
DISPLAY INVISIBLE (-4225 7325);
FORCEPROP 2 LAST CDS_LOCATION R4733
J 0
(-4225 7375);
DISPLAY 1.021277 (-4225 7375);
DISPLAY INVISIBLE (-4225 7375);
FORCEPROP 2 LAST $SEC 1
J 0
(-4225 7375);
DISPLAY 0.680851 (-4225 7375);
PAINT MONO (-4225 7375);
DISPLAY INVISIBLE (-4225 7375);
FORCEPROP 2 LAST CDS_SEC 1
J 0
(-4225 7375);
DISPLAY 1.021277 (-4225 7375);
DISPLAY INVISIBLE (-4225 7375);
FORCEADD MOSFET_NCH_DUAL..2
(-4325 6725);
FORCEPROP 1 LAST PART_NUMBER BAM138K0003
J 0
(-4174 6631);
DISPLAY 0.723404 (-4174 6631);
PAINT GREEN (-4174 6631);
DISPLAY INVISIBLE (-4174 6631);
FORCEPROP 2 LAST VALUE PJT138K
J 0
(-4150 6750);
DISPLAY 1.021277 (-4150 6750);
FORCEPROP 2 LAST PART_TYPE SMLF
J 0
(-4150 6800);
DISPLAY 1.021277 (-4150 6800);
FORCEPROP 1 LAST MATERIAL IC
J 0
(-4174 6576);
DISPLAY 0.723404 (-4174 6576);
PAINT GREEN (-4174 6576);
FORCEPROP 1 LAST LOCATION Q152
J 0
(-4174 6701);
DISPLAY 0.723404 (-4174 6701);
PAINT GREEN (-4174 6701);
FORCEPROP 0 LASTPIN (-4275 6925) $PN 3
R 1
J 0
(-4285 6935);
DISPLAY 0.680851 (-4285 6935);
PAINT MONO (-4285 6935);
FORCEPROP 0 LASTPIN (-4525 6675) $PN 5
J 2
(-4535 6685);
DISPLAY 0.680851 (-4535 6685);
PAINT MONO (-4535 6685);
FORCEPROP 0 LASTPIN (-4275 6525) $PN 4
R 1
J 2
(-4285 6515);
DISPLAY 0.680851 (-4285 6515);
PAINT MONO (-4285 6515);
FORCEPROP 2 LAST CDS_LIB pure_quanta
J 0
(-4325 6725);
DISPLAY INVISIBLE (-4325 6725);
FORCEPROP 1 LAST NEEDS_NO_SIZE TRUE
J 0
(-4175 6616);
DISPLAY 0.468085 (-4175 6616);
PAINT GREEN (-4175 6616);
DISPLAY INVISIBLE (-4175 6616);
FORCEPROP 1 LAST CDS_LMAN_SYM_OUTLINE -150,150,150,-150
J 0
(-4325 6725);
DISPLAY 0.468085 (-4325 6725);
PAINT GREEN (-4325 6725);
DISPLAY INVISIBLE (-4325 6725);
FORCEPROP 1 LAST PATH I26
J 0
(-4175 6575);
DISPLAY 0.723404 (-4175 6575);
PAINT GREEN (-4175 6575);
DISPLAY INVISIBLE (-4175 6575);
FORCEPROP 0 LAST $SEC 2
J 0
(-4150 6850);
DISPLAY 0.680851 (-4150 6850);
PAINT MONO (-4150 6850);
DISPLAY INVISIBLE (-4150 6850);
FORCEPROP 0 LAST CDS_SEC 2
J 0
(-4150 6850);
DISPLAY 1.021277 (-4150 6850);
DISPLAY INVISIBLE (-4150 6850);
FORCEADD UNIVERSAL_GND..1
(-4275 6350);
FORCEPROP 3 LASTPIN (-4275 6400) SIG_NAME GND\g
J 0
(-4265 6410);
DISPLAY 0.659574 (-4265 6410);
PAINT MONO (-4265 6410);
DISPLAY INVISIBLE (-4265 6410);
FORCEPROP 1 LAST HDL_POWER GND
J 1
(-4250 6275);
DISPLAY 0.872340 (-4250 6275);
PAINT GREEN (-4250 6275);
DISPLAY INVISIBLE (-4250 6275);
FORCEPROP 2 LAST CDS_LIB logical_power
J 0
(-4275 6350);
DISPLAY INVISIBLE (-4275 6350);
FORCEPROP 1 LAST PATH I27
J 0
(-4200 6350);
DISPLAY 0.872340 (-4200 6350);
PAINT AQUA (-4200 6350);
DISPLAY INVISIBLE (-4200 6350);
FORCEADD Q_RES..2
(-5550 8550);
FORCEPROP 1 LAST PART_NUMBER CS24702JB10
J 0
(-5510 8375);
DISPLAY 0.638298 (-5510 8375);
DISPLAY INVISIBLE (-5510 8375);
FORCEPROP 1 LAST TOLERANCE 5%
J 0
(-5505 8575);
DISPLAY 0.638298 (-5505 8575);
FORCEPROP 1 LAST PACK_TYPE 0402LF
J 0
(-5510 8425);
DISPLAY 0.638298 (-5510 8425);
FORCEPROP 1 LAST WATTAGE 1/16W
J 0
(-5510 8525);
DISPLAY 0.638298 (-5510 8525);
FORCEPROP 1 LAST MATERIAL CHIP
J 0
(-5510 8475);
DISPLAY 0.638298 (-5510 8475);
FORCEPROP 1 LAST VALUE 4.7K
J 0
(-5505 8625);
DISPLAY 0.638298 (-5505 8625);
FORCEPROP 1 LAST $LOCATION R4725
J 0
(-5505 8675);
DISPLAY 0.638298 (-5505 8675);
FORCEPROP 1 LASTPIN (-5550 8650) $PN 1
J 0
(-5545 8612);
DISPLAY 0.787234 (-5545 8612);
FORCEPROP 1 LASTPIN (-5550 8450) $PN 2
J 0
(-5545 8460);
DISPLAY 0.787234 (-5545 8460);
FORCEPROP 1 LAST PATH I28
J 0
(-5500 8725);
DISPLAY 0.978723 (-5500 8725);
PAINT WHITE (-5500 8725);
DISPLAY INVISIBLE (-5500 8725);
FORCEPROP 2 LAST CDS_LIB pure_quanta
J 0
(-5550 8550);
PAINT MONO (-5550 8550);
DISPLAY INVISIBLE (-5550 8550);
FORCEPROP 2 LAST CDS_LOCATION R4725
J 0
(-5500 8775);
DISPLAY 1.021277 (-5500 8775);
DISPLAY INVISIBLE (-5500 8775);
FORCEPROP 2 LAST $SEC 1
J 0
(-5500 8775);
DISPLAY 0.680851 (-5500 8775);
PAINT MONO (-5500 8775);
DISPLAY INVISIBLE (-5500 8775);
FORCEPROP 2 LAST CDS_SEC 1
J 0
(-5500 8775);
DISPLAY 1.021277 (-5500 8775);
DISPLAY INVISIBLE (-5500 8775);
FORCEADD UNIVERSAL_POWER..1
(-5550 8775);
FORCEPROP 3 LASTPIN (-5550 8725) SIG_NAME P3V3_AUX\g
J 0
(-5540 8735);
DISPLAY 0.659574 (-5540 8735);
PAINT MONO (-5540 8735);
DISPLAY INVISIBLE (-5540 8735);
FORCEPROP 1 LAST HDL_POWER P3V3_AUX
J 1
(-5550 8825);
DISPLAY 0.872340 (-5550 8825);
PAINT GREEN (-5550 8825);
FORCEPROP 1 LAST PATH I29
J 0
(-5500 8800);
DISPLAY 0.872340 (-5500 8800);
PAINT AQUA (-5500 8800);
DISPLAY INVISIBLE (-5500 8800);
FORCEPROP 2 LAST CDS_LIB logical_power
J 0
(-5550 8775);
PAINT MONO (-5550 8775);
DISPLAY INVISIBLE (-5550 8775);
FORCEADD OFFPAGE..2
R 2
(-675 3850);
FORCEPROP 2 LAST $XR1 227 
J 0
(-1050 3850);
DISPLAY 0.638298 (-1050 3850);
PAINT MONO (-1050 3850);
FORCEPROP 2 LAST $XR0 142 
J 0
(-930 3850);
DISPLAY 0.638298 (-930 3850);
PAINT MONO (-930 3850);
FORCEPROP 1 LAST OFFPAGE TRUE
J 2
(-1000 3725);
DISPLAY 0.872340 (-1000 3725);
PAINT AQUA (-1000 3725);
DISPLAY INVISIBLE (-1000 3725);
FORCEPROP 1 LAST COMMENT_BODY TRUE
J 2
(-630 3755);
DISPLAY 0.872340 (-630 3755);
PAINT GREEN (-630 3755);
DISPLAY INVISIBLE (-630 3755);
FORCEPROP 2 LAST CDS_LIB standard
J 0
(-675 3850);
DISPLAY INVISIBLE (-675 3850);
FORCEPROP 2 LAST PATH I3
J 0
(-925 3900);
DISPLAY 1.021277 (-925 3900);
DISPLAY INVISIBLE (-925 3900);
FORCEADD UNIVERSAL_GND..1
(-5550 7575);
FORCEPROP 3 LASTPIN (-5550 7625) SIG_NAME GND\g
J 0
(-5540 7635);
DISPLAY 0.659574 (-5540 7635);
PAINT MONO (-5540 7635);
DISPLAY INVISIBLE (-5540 7635);
FORCEPROP 1 LAST PATH I30
J 0
(-5475 7575);
DISPLAY 0.872340 (-5475 7575);
PAINT AQUA (-5475 7575);
DISPLAY INVISIBLE (-5475 7575);
FORCEPROP 2 LAST CDS_LIB logical_power
J 0
(-5550 7575);
DISPLAY INVISIBLE (-5550 7575);
FORCEPROP 1 LAST HDL_POWER GND
J 1
(-5525 7500);
DISPLAY 0.872340 (-5525 7500);
PAINT GREEN (-5525 7500);
DISPLAY INVISIBLE (-5525 7500);
FORCEADD MOSFET_NCH_DUAL..1
(-5600 7950);
FORCEPROP 1 LAST PART_NUMBER BAM138K0003
J 0
(-5449 7864);
DISPLAY 0.723404 (-5449 7864);
PAINT GREEN (-5449 7864);
DISPLAY INVISIBLE (-5449 7864);
FORCEPROP 2 LAST PART_TYPE SMLF
J 0
(-5425 8025);
DISPLAY 1.021277 (-5425 8025);
FORCEPROP 1 LAST MATERIAL IC
J 0
(-5449 7799);
DISPLAY 0.723404 (-5449 7799);
PAINT GREEN (-5449 7799);
FORCEPROP 2 LAST VALUE PJT138K
J 0
(-5425 7975);
DISPLAY 1.021277 (-5425 7975);
FORCEPROP 1 LAST $LOCATION Q151
J 0
(-5449 7924);
DISPLAY 0.723404 (-5449 7924);
PAINT GREEN (-5449 7924);
FORCEPROP 0 LASTPIN (-5550 8150) $PN 6
R 1
J 0
(-5560 8160);
DISPLAY 0.680851 (-5560 8160);
PAINT MONO (-5560 8160);
FORCEPROP 0 LASTPIN (-5800 7900) $PN 2
J 2
(-5810 7910);
DISPLAY 0.680851 (-5810 7910);
PAINT MONO (-5810 7910);
FORCEPROP 0 LASTPIN (-5550 7750) $PN 1
R 1
J 2
(-5560 7740);
DISPLAY 0.680851 (-5560 7740);
PAINT MONO (-5560 7740);
FORCEPROP 1 LAST PATH I31
J 0
(-5600 7950);
DISPLAY 0.723404 (-5600 7950);
PAINT GREEN (-5600 7950);
DISPLAY INVISIBLE (-5600 7950);
FORCEPROP 2 LAST CDS_LIB pure_quanta
J 0
(-5600 7950);
DISPLAY INVISIBLE (-5600 7950);
FORCEPROP 1 LAST NEEDS_NO_SIZE TRUE
J 0
(-5600 7949);
DISPLAY 0.468085 (-5600 7949);
PAINT GREEN (-5600 7949);
DISPLAY INVISIBLE (-5600 7949);
FORCEPROP 1 LAST CDS_LMAN_SYM_OUTLINE -150,150,150,-150
J 0
(-5600 7950);
DISPLAY 0.468085 (-5600 7950);
PAINT GREEN (-5600 7950);
DISPLAY INVISIBLE (-5600 7950);
FORCEPROP 2 LAST CDS_LOCATION Q151
J 0
(-5425 8075);
DISPLAY 1.021277 (-5425 8075);
DISPLAY INVISIBLE (-5425 8075);
FORCEPROP 0 LAST $SEC 1
J 0
(-5425 8075);
DISPLAY 0.680851 (-5425 8075);
PAINT MONO (-5425 8075);
DISPLAY INVISIBLE (-5425 8075);
FORCEPROP 2 LAST CDS_SEC 1
J 0
(-5425 8075);
DISPLAY 1.021277 (-5425 8075);
DISPLAY INVISIBLE (-5425 8075);
FORCEADD UNIVERSAL_POWER..1
(-6725 8425);
FORCEPROP 3 LASTPIN (-6725 8375) SIG_NAME P3V3_AUX\g
J 0
(-6715 8385);
DISPLAY 0.659574 (-6715 8385);
PAINT MONO (-6715 8385);
DISPLAY INVISIBLE (-6715 8385);
FORCEPROP 1 LAST HDL_POWER P3V3_AUX
J 1
(-6725 8475);
DISPLAY 0.872340 (-6725 8475);
PAINT GREEN (-6725 8475);
FORCEPROP 1 LAST PATH I32
J 0
(-6675 8450);
DISPLAY 0.872340 (-6675 8450);
PAINT AQUA (-6675 8450);
DISPLAY INVISIBLE (-6675 8450);
FORCEPROP 2 LAST CDS_LIB logical_power
J 0
(-6725 8425);
PAINT MONO (-6725 8425);
DISPLAY INVISIBLE (-6725 8425);
FORCEADD Q_RES..2
(-6725 8175);
FORCEPROP 1 LAST PART_NUMBER CS31002FB08
J 0
(-6685 8050);
DISPLAY 0.510638 (-6685 8050);
DISPLAY INVISIBLE (-6685 8050);
FORCEPROP 1 LAST MATERIAL CHIP
J 0
(-6685 8100);
DISPLAY 0.510638 (-6685 8100);
FORCEPROP 1 LAST TOLERANCE 1%
J 0
(-6680 8200);
DISPLAY 0.510638 (-6680 8200);
FORCEPROP 1 LAST PACK_TYPE 0402LF
J 0
(-6685 8000);
DISPLAY 0.510638 (-6685 8000);
FORCEPROP 1 LAST VALUE 10K
J 0
(-6680 8250);
DISPLAY 0.510638 (-6680 8250);
FORCEPROP 1 LAST WATTAGE 1/16W
J 0
(-6685 8150);
DISPLAY 0.510638 (-6685 8150);
FORCEPROP 1 LAST $LOCATION R4727
J 0
(-6680 8300);
DISPLAY 0.978723 (-6680 8300);
FORCEPROP 1 LASTPIN (-6725 8275) $PN 1
J 0
(-6720 8237);
DISPLAY 0.787234 (-6720 8237);
PAINT MONO (-6720 8237);
FORCEPROP 1 LASTPIN (-6725 8075) $PN 2
J 0
(-6720 8085);
DISPLAY 0.787234 (-6720 8085);
PAINT MONO (-6720 8085);
FORCEPROP 1 LAST PATH I33
J 0
(-6675 8350);
DISPLAY 0.978723 (-6675 8350);
PAINT WHITE (-6675 8350);
DISPLAY INVISIBLE (-6675 8350);
FORCEPROP 2 LAST CDS_LIB pure_quanta
J 0
(-6725 8175);
DISPLAY INVISIBLE (-6725 8175);
FORCEPROP 0 LAST CDS_LOCATION R4727
J 0
(-6675 8350);
DISPLAY 1.021277 (-6675 8350);
DISPLAY INVISIBLE (-6675 8350);
FORCEPROP 0 LAST $SEC 1
J 0
(-6675 8350);
DISPLAY 0.680851 (-6675 8350);
PAINT MONO (-6675 8350);
DISPLAY INVISIBLE (-6675 8350);
FORCEPROP 0 LAST CDS_SEC 1
J 0
(-6675 8350);
DISPLAY 1.021277 (-6675 8350);
DISPLAY INVISIBLE (-6675 8350);
FORCEADD Q_RES..2
(-6700 7700);
FORCEPROP 1 LAST PART_NUMBER CS41002FB09
J 0
(-6660 7575);
DISPLAY 0.510638 (-6660 7575);
DISPLAY INVISIBLE (-6660 7575);
FORCEPROP 1 LAST MATERIAL EMPTY
J 0
(-6660 7625);
DISPLAY 0.510638 (-6660 7625);
PAINT RED (-6660 7625);
FORCEPROP 1 LAST PACK_TYPE 0402LF
J 0
(-6660 7525);
DISPLAY 0.510638 (-6660 7525);
FORCEPROP 1 LAST WATTAGE 1/16W
J 0
(-6660 7675);
DISPLAY 0.510638 (-6660 7675);
FORCEPROP 1 LAST TOLERANCE 1%
J 0
(-6655 7725);
DISPLAY 0.510638 (-6655 7725);
FORCEPROP 1 LAST VALUE 100K
J 0
(-6655 7775);
DISPLAY 0.510638 (-6655 7775);
FORCEPROP 1 LAST $LOCATION R4724
J 0
(-6655 7825);
DISPLAY 0.978723 (-6655 7825);
FORCEPROP 1 LASTPIN (-6700 7800) $PN 1
J 0
(-6695 7762);
DISPLAY 0.787234 (-6695 7762);
PAINT MONO (-6695 7762);
FORCEPROP 1 LASTPIN (-6700 7600) $PN 2
J 0
(-6695 7610);
DISPLAY 0.787234 (-6695 7610);
PAINT MONO (-6695 7610);
FORCEPROP 1 LAST PATH I34
J 0
(-6650 7875);
DISPLAY 0.978723 (-6650 7875);
PAINT WHITE (-6650 7875);
DISPLAY INVISIBLE (-6650 7875);
FORCEPROP 2 LAST CDS_LIB pure_quanta
J 0
(-6700 7700);
DISPLAY INVISIBLE (-6700 7700);
FORCEPROP 0 LAST CDS_LOCATION R4724
J 0
(-6650 7875);
DISPLAY 1.021277 (-6650 7875);
DISPLAY INVISIBLE (-6650 7875);
FORCEPROP 0 LAST $SEC 1
J 0
(-6650 7875);
DISPLAY 0.680851 (-6650 7875);
PAINT MONO (-6650 7875);
DISPLAY INVISIBLE (-6650 7875);
FORCEPROP 0 LAST CDS_SEC 1
J 0
(-6650 7875);
DISPLAY 1.021277 (-6650 7875);
DISPLAY INVISIBLE (-6650 7875);
FORCEADD UNIVERSAL_POWER..1
(-5425 7250);
FORCEPROP 3 LASTPIN (-5425 7200) SIG_NAME P3V3_AUX\g
J 0
(-5415 7210);
DISPLAY 0.659574 (-5415 7210);
PAINT MONO (-5415 7210);
DISPLAY INVISIBLE (-5415 7210);
FORCEPROP 1 LAST HDL_POWER P3V3_AUX
J 1
(-5425 7300);
DISPLAY 0.872340 (-5425 7300);
PAINT GREEN (-5425 7300);
FORCEPROP 2 LAST CDS_LIB logical_power
J 0
(-5425 7250);
PAINT MONO (-5425 7250);
DISPLAY INVISIBLE (-5425 7250);
FORCEPROP 1 LAST PATH I35
J 0
(-5375 7275);
DISPLAY 0.872340 (-5375 7275);
PAINT AQUA (-5375 7275);
DISPLAY INVISIBLE (-5375 7275);
FORCEADD Q_RES..2
(-5425 7025);
FORCEPROP 1 LAST PART_NUMBER CS24702JB10
J 0
(-5385 6850);
DISPLAY 0.638298 (-5385 6850);
DISPLAY INVISIBLE (-5385 6850);
FORCEPROP 1 LAST VALUE 4.7K
J 0
(-5380 7100);
DISPLAY 0.638298 (-5380 7100);
FORCEPROP 1 LAST MATERIAL CHIP
J 0
(-5385 6950);
DISPLAY 0.638298 (-5385 6950);
FORCEPROP 1 LAST TOLERANCE 5%
J 0
(-5380 7050);
DISPLAY 0.638298 (-5380 7050);
FORCEPROP 1 LAST WATTAGE 1/16W
J 0
(-5385 7000);
DISPLAY 0.638298 (-5385 7000);
FORCEPROP 1 LAST PACK_TYPE 0402LF
J 0
(-5385 6900);
DISPLAY 0.638298 (-5385 6900);
FORCEPROP 1 LAST $LOCATION R4732
J 0
(-5380 7150);
DISPLAY 0.638298 (-5380 7150);
FORCEPROP 1 LASTPIN (-5425 7125) $PN 1
J 0
(-5420 7087);
DISPLAY 0.787234 (-5420 7087);
FORCEPROP 1 LASTPIN (-5425 6925) $PN 2
J 0
(-5420 6935);
DISPLAY 0.787234 (-5420 6935);
FORCEPROP 2 LAST CDS_LIB pure_quanta
J 0
(-5425 7025);
PAINT MONO (-5425 7025);
DISPLAY INVISIBLE (-5425 7025);
FORCEPROP 1 LAST PATH I36
J 0
(-5375 7200);
DISPLAY 0.978723 (-5375 7200);
PAINT WHITE (-5375 7200);
DISPLAY INVISIBLE (-5375 7200);
FORCEPROP 2 LAST CDS_LOCATION R4732
J 0
(-5375 7250);
DISPLAY 1.021277 (-5375 7250);
DISPLAY INVISIBLE (-5375 7250);
FORCEPROP 2 LAST $SEC 1
J 0
(-5375 7250);
DISPLAY 0.680851 (-5375 7250);
PAINT MONO (-5375 7250);
DISPLAY INVISIBLE (-5375 7250);
FORCEPROP 2 LAST CDS_SEC 1
J 0
(-5375 7250);
DISPLAY 1.021277 (-5375 7250);
DISPLAY INVISIBLE (-5375 7250);
FORCEADD UNIVERSAL_GND..1
(-5425 6050);
FORCEPROP 3 LASTPIN (-5425 6100) SIG_NAME GND\g
J 0
(-5415 6110);
DISPLAY 0.659574 (-5415 6110);
PAINT MONO (-5415 6110);
DISPLAY INVISIBLE (-5415 6110);
FORCEPROP 2 LAST CDS_LIB logical_power
J 0
(-5425 6050);
DISPLAY INVISIBLE (-5425 6050);
FORCEPROP 1 LAST HDL_POWER GND
J 1
(-5400 5975);
DISPLAY 0.872340 (-5400 5975);
PAINT GREEN (-5400 5975);
DISPLAY INVISIBLE (-5400 5975);
FORCEPROP 1 LAST PATH I37
J 0
(-5350 6050);
DISPLAY 0.872340 (-5350 6050);
PAINT AQUA (-5350 6050);
DISPLAY INVISIBLE (-5350 6050);
FORCEADD MOSFET_NCH_DUAL..1
(-5475 6425);
FORCEPROP 1 LAST PART_NUMBER BAM138K0003
J 0
(-5324 6339);
DISPLAY 0.723404 (-5324 6339);
PAINT GREEN (-5324 6339);
DISPLAY INVISIBLE (-5324 6339);
FORCEPROP 2 LAST VALUE PJT138K
J 0
(-5300 6450);
DISPLAY 1.021277 (-5300 6450);
FORCEPROP 2 LAST PART_TYPE SMLF
J 0
(-5300 6500);
DISPLAY 1.021277 (-5300 6500);
FORCEPROP 1 LAST MATERIAL IC
J 0
(-5324 6274);
DISPLAY 0.723404 (-5324 6274);
PAINT GREEN (-5324 6274);
FORCEPROP 1 LAST $LOCATION Q152
J 0
(-5324 6399);
DISPLAY 0.723404 (-5324 6399);
PAINT GREEN (-5324 6399);
FORCEPROP 0 LASTPIN (-5425 6625) $PN 6
R 1
J 0
(-5435 6635);
DISPLAY 0.680851 (-5435 6635);
PAINT MONO (-5435 6635);
FORCEPROP 0 LASTPIN (-5675 6375) $PN 2
J 2
(-5685 6385);
DISPLAY 0.680851 (-5685 6385);
PAINT MONO (-5685 6385);
FORCEPROP 0 LASTPIN (-5425 6225) $PN 1
R 1
J 2
(-5435 6215);
DISPLAY 0.680851 (-5435 6215);
PAINT MONO (-5435 6215);
FORCEPROP 1 LAST CDS_LMAN_SYM_OUTLINE -150,150,150,-150
J 0
(-5475 6425);
DISPLAY 0.468085 (-5475 6425);
PAINT GREEN (-5475 6425);
DISPLAY INVISIBLE (-5475 6425);
FORCEPROP 1 LAST NEEDS_NO_SIZE TRUE
J 0
(-5475 6424);
DISPLAY 0.468085 (-5475 6424);
PAINT GREEN (-5475 6424);
DISPLAY INVISIBLE (-5475 6424);
FORCEPROP 2 LAST CDS_LIB pure_quanta
J 0
(-5475 6425);
DISPLAY INVISIBLE (-5475 6425);
FORCEPROP 1 LAST PATH I38
J 0
(-5475 6425);
DISPLAY 0.723404 (-5475 6425);
PAINT GREEN (-5475 6425);
DISPLAY INVISIBLE (-5475 6425);
FORCEPROP 2 LAST CDS_LOCATION Q152
J 0
(-5300 6550);
DISPLAY 1.021277 (-5300 6550);
DISPLAY INVISIBLE (-5300 6550);
FORCEPROP 0 LAST $SEC 1
J 0
(-5300 6550);
DISPLAY 0.680851 (-5300 6550);
PAINT MONO (-5300 6550);
DISPLAY INVISIBLE (-5300 6550);
FORCEPROP 2 LAST CDS_SEC 1
J 0
(-5300 6550);
DISPLAY 1.021277 (-5300 6550);
DISPLAY INVISIBLE (-5300 6550);
FORCEADD UNIVERSAL_GND..1
(-6700 7425);
FORCEPROP 3 LASTPIN (-6700 7475) SIG_NAME GND\g
J 0
(-6690 7485);
DISPLAY 0.659574 (-6690 7485);
PAINT MONO (-6690 7485);
DISPLAY INVISIBLE (-6690 7485);
FORCEPROP 1 LAST PATH I39
J 0
(-6625 7425);
DISPLAY 0.872340 (-6625 7425);
PAINT AQUA (-6625 7425);
DISPLAY INVISIBLE (-6625 7425);
FORCEPROP 1 LAST HDL_POWER GND
J 1
(-6675 7350);
DISPLAY 0.872340 (-6675 7350);
PAINT GREEN (-6675 7350);
DISPLAY INVISIBLE (-6675 7350);
FORCEPROP 2 LAST CDS_LIB logical_power
J 0
(-6700 7425);
DISPLAY INVISIBLE (-6700 7425);
FORCEADD OFFPAGE..2
R 2
(-675 4050);
FORCEPROP 2 LAST $XR1 227 
J 0
(-1050 4050);
DISPLAY 0.638298 (-1050 4050);
PAINT MONO (-1050 4050);
FORCEPROP 2 LAST $XR0 142 
J 0
(-930 4050);
DISPLAY 0.638298 (-930 4050);
PAINT MONO (-930 4050);
FORCEPROP 2 LAST CDS_LIB standard
J 0
(-675 4050);
DISPLAY INVISIBLE (-675 4050);
FORCEPROP 1 LAST COMMENT_BODY TRUE
J 2
(-630 3955);
DISPLAY 0.872340 (-630 3955);
PAINT GREEN (-630 3955);
DISPLAY INVISIBLE (-630 3955);
FORCEPROP 1 LAST OFFPAGE TRUE
J 2
(-1000 3925);
DISPLAY 0.872340 (-1000 3925);
PAINT AQUA (-1000 3925);
DISPLAY INVISIBLE (-1000 3925);
FORCEPROP 2 LAST PATH I4
J 0
(-925 4100);
DISPLAY 1.021277 (-925 4100);
DISPLAY INVISIBLE (-925 4100);
FORCEADD UNIVERSAL_POWER..1
(-6600 6900);
FORCEPROP 3 LASTPIN (-6600 6850) SIG_NAME P3V3_AUX\g
J 0
(-6590 6860);
DISPLAY 0.659574 (-6590 6860);
PAINT MONO (-6590 6860);
DISPLAY INVISIBLE (-6590 6860);
FORCEPROP 1 LAST HDL_POWER P3V3_AUX
J 1
(-6600 6950);
DISPLAY 0.872340 (-6600 6950);
PAINT GREEN (-6600 6950);
FORCEPROP 2 LAST CDS_LIB logical_power
J 0
(-6600 6900);
PAINT MONO (-6600 6900);
DISPLAY INVISIBLE (-6600 6900);
FORCEPROP 1 LAST PATH I40
J 0
(-6550 6925);
DISPLAY 0.872340 (-6550 6925);
PAINT AQUA (-6550 6925);
DISPLAY INVISIBLE (-6550 6925);
FORCEADD Q_RES..2
(-6600 6650);
FORCEPROP 1 LAST PART_NUMBER CS31002FB08
J 0
(-6560 6525);
DISPLAY 0.510638 (-6560 6525);
DISPLAY INVISIBLE (-6560 6525);
FORCEPROP 1 LAST TOLERANCE 1%
J 0
(-6555 6675);
DISPLAY 0.510638 (-6555 6675);
FORCEPROP 1 LAST VALUE 10K
J 0
(-6555 6725);
DISPLAY 0.510638 (-6555 6725);
FORCEPROP 1 LAST WATTAGE 1/16W
J 0
(-6560 6625);
DISPLAY 0.510638 (-6560 6625);
FORCEPROP 1 LAST MATERIAL CHIP
J 0
(-6560 6575);
DISPLAY 0.510638 (-6560 6575);
FORCEPROP 1 LAST PACK_TYPE 0402LF
J 0
(-6560 6475);
DISPLAY 0.510638 (-6560 6475);
FORCEPROP 1 LAST $LOCATION R4730
J 0
(-6555 6775);
DISPLAY 0.978723 (-6555 6775);
FORCEPROP 1 LASTPIN (-6600 6750) $PN 1
J 0
(-6595 6712);
DISPLAY 0.787234 (-6595 6712);
PAINT MONO (-6595 6712);
FORCEPROP 1 LASTPIN (-6600 6550) $PN 2
J 0
(-6595 6560);
DISPLAY 0.787234 (-6595 6560);
PAINT MONO (-6595 6560);
FORCEPROP 2 LAST CDS_LIB pure_quanta
J 0
(-6600 6650);
DISPLAY INVISIBLE (-6600 6650);
FORCEPROP 1 LAST PATH I41
J 0
(-6550 6825);
DISPLAY 0.978723 (-6550 6825);
PAINT WHITE (-6550 6825);
DISPLAY INVISIBLE (-6550 6825);
FORCEPROP 0 LAST CDS_LOCATION R4730
J 0
(-6550 6825);
DISPLAY 1.021277 (-6550 6825);
DISPLAY INVISIBLE (-6550 6825);
FORCEPROP 0 LAST $SEC 1
J 0
(-6550 6825);
DISPLAY 0.680851 (-6550 6825);
PAINT MONO (-6550 6825);
DISPLAY INVISIBLE (-6550 6825);
FORCEPROP 0 LAST CDS_SEC 1
J 0
(-6550 6825);
DISPLAY 1.021277 (-6550 6825);
DISPLAY INVISIBLE (-6550 6825);
FORCEADD Q_RES..2
(-6575 6175);
FORCEPROP 1 LAST PART_NUMBER CS41002FB09
J 0
(-6535 6050);
DISPLAY 0.510638 (-6535 6050);
DISPLAY INVISIBLE (-6535 6050);
FORCEPROP 1 LAST WATTAGE 1/16W
J 0
(-6535 6150);
DISPLAY 0.510638 (-6535 6150);
FORCEPROP 1 LAST MATERIAL EMPTY
J 0
(-6535 6100);
DISPLAY 0.510638 (-6535 6100);
PAINT RED (-6535 6100);
FORCEPROP 1 LAST TOLERANCE 1%
J 0
(-6530 6200);
DISPLAY 0.510638 (-6530 6200);
FORCEPROP 1 LAST VALUE 100K
J 0
(-6530 6250);
DISPLAY 0.510638 (-6530 6250);
FORCEPROP 1 LAST PACK_TYPE 0402LF
J 0
(-6535 6000);
DISPLAY 0.510638 (-6535 6000);
FORCEPROP 1 LAST $LOCATION R4731
J 0
(-6530 6300);
DISPLAY 0.978723 (-6530 6300);
FORCEPROP 1 LASTPIN (-6575 6275) $PN 1
J 0
(-6570 6237);
DISPLAY 0.787234 (-6570 6237);
PAINT MONO (-6570 6237);
FORCEPROP 1 LASTPIN (-6575 6075) $PN 2
J 0
(-6570 6085);
DISPLAY 0.787234 (-6570 6085);
PAINT MONO (-6570 6085);
FORCEPROP 2 LAST CDS_LIB pure_quanta
J 0
(-6575 6175);
DISPLAY INVISIBLE (-6575 6175);
FORCEPROP 1 LAST PATH I42
J 0
(-6525 6350);
DISPLAY 0.978723 (-6525 6350);
PAINT WHITE (-6525 6350);
DISPLAY INVISIBLE (-6525 6350);
FORCEPROP 0 LAST CDS_LOCATION R4731
J 0
(-6525 6350);
DISPLAY 1.021277 (-6525 6350);
DISPLAY INVISIBLE (-6525 6350);
FORCEPROP 0 LAST $SEC 1
J 0
(-6525 6350);
DISPLAY 0.680851 (-6525 6350);
PAINT MONO (-6525 6350);
DISPLAY INVISIBLE (-6525 6350);
FORCEPROP 0 LAST CDS_SEC 1
J 0
(-6525 6350);
DISPLAY 1.021277 (-6525 6350);
DISPLAY INVISIBLE (-6525 6350);
FORCEADD UNIVERSAL_GND..1
(-6575 5900);
FORCEPROP 3 LASTPIN (-6575 5950) SIG_NAME GND\g
J 0
(-6565 5960);
DISPLAY 0.659574 (-6565 5960);
PAINT MONO (-6565 5960);
DISPLAY INVISIBLE (-6565 5960);
FORCEPROP 1 LAST PATH I43
J 0
(-6500 5900);
DISPLAY 0.872340 (-6500 5900);
PAINT AQUA (-6500 5900);
DISPLAY INVISIBLE (-6500 5900);
FORCEPROP 2 LAST CDS_LIB logical_power
J 0
(-6575 5900);
DISPLAY INVISIBLE (-6575 5900);
FORCEPROP 1 LAST HDL_POWER GND
J 1
(-6550 5825);
DISPLAY 0.872340 (-6550 5825);
PAINT GREEN (-6550 5825);
DISPLAY INVISIBLE (-6550 5825);
FORCEADD OFFPAGE..4
R 2
(-6850 6375);
FORCEPROP 2 LAST $XR0 138 
J 0
(-7132 6375);
DISPLAY 0.638298 (-7132 6375);
PAINT MONO (-7132 6375);
FORCEPROP 1 LAST OFFPAGE TRUE
J 2
(-7175 6250);
DISPLAY 0.872340 (-7175 6250);
PAINT GREEN (-7175 6250);
DISPLAY INVISIBLE (-7175 6250);
FORCEPROP 1 LAST COMMENT_BODY TRUE
J 2
(-6825 6275);
DISPLAY 0.872340 (-6825 6275);
PAINT GREEN (-6825 6275);
DISPLAY INVISIBLE (-6825 6275);
FORCEPROP 2 LAST CDS_LIB standard
J 0
(-6850 6375);
DISPLAY INVISIBLE (-6850 6375);
FORCEPROP 2 LAST PATH I44
J 0
(-7100 6425);
DISPLAY 1.021277 (-7100 6425);
DISPLAY INVISIBLE (-7100 6425);
FORCEADD OFFPAGE..4
R 2
(-6975 7900);
FORCEPROP 2 LAST $XR0 143 
J 0
(-7257 7900);
DISPLAY 0.638298 (-7257 7900);
PAINT MONO (-7257 7900);
FORCEPROP 2 LAST PATH I45
J 0
(-7225 7950);
DISPLAY 1.021277 (-7225 7950);
DISPLAY INVISIBLE (-7225 7950);
FORCEPROP 1 LAST OFFPAGE TRUE
J 2
(-7300 7775);
DISPLAY 0.872340 (-7300 7775);
PAINT GREEN (-7300 7775);
DISPLAY INVISIBLE (-7300 7775);
FORCEPROP 1 LAST COMMENT_BODY TRUE
J 2
(-6950 7800);
DISPLAY 0.872340 (-6950 7800);
PAINT GREEN (-6950 7800);
DISPLAY INVISIBLE (-6950 7800);
FORCEPROP 2 LAST CDS_LIB standard
J 0
(-6975 7900);
DISPLAY INVISIBLE (-6975 7900);
FORCEADD OFFPAGE..2
(-2925 5325);
FORCEPROP 2 LAST $XR0 227 
J 0
(-2736 5325);
DISPLAY 0.638298 (-2736 5325);
PAINT MONO (-2736 5325);
FORCEPROP 2 LAST PATH I46
J 0
(-2725 5375);
DISPLAY 1.021277 (-2725 5375);
DISPLAY INVISIBLE (-2725 5375);
FORCEPROP 1 LAST OFFPAGE TRUE
J 0
(-2600 5200);
DISPLAY 0.872340 (-2600 5200);
PAINT AQUA (-2600 5200);
DISPLAY INVISIBLE (-2600 5200);
FORCEPROP 1 LAST COMMENT_BODY TRUE
J 0
(-2970 5230);
DISPLAY 0.872340 (-2970 5230);
PAINT GREEN (-2970 5230);
DISPLAY INVISIBLE (-2970 5230);
FORCEPROP 2 LAST CDS_LIB standard
J 0
(-2925 5325);
DISPLAY INVISIBLE (-2925 5325);
FORCEADD Q_CAP..1
(-3275 5025);
FORCEPROP 1 LAST PART_NUMBER TMP_QCH21006JB10
J 0
(-3225 4875);
DISPLAY 0.638298 (-3225 4875);
DISPLAY INVISIBLE (-3225 4875);
FORCEPROP 1 LAST VOLTAGE 50V
J 0
(-3225 5025);
DISPLAY 0.638298 (-3225 5025);
FORCEPROP 1 LAST PACK_TYPE 0402
J 0
(-3225 4825);
DISPLAY 0.638298 (-3225 4825);
FORCEPROP 1 LAST TOLERANCE 5%
J 0
(-3225 4975);
DISPLAY 0.638298 (-3225 4975);
FORCEPROP 1 LAST VALUE 1000PF
J 0
(-3225 5075);
DISPLAY 0.638298 (-3225 5075);
FORCEPROP 1 LAST MATERIAL EMPTY
J 0
(-3225 4925);
DISPLAY 0.638298 (-3225 4925);
PAINT RED (-3225 4925);
FORCEPROP 1 LAST $LOCATION C2374
J 0
(-3225 5125);
DISPLAY 0.978723 (-3225 5125);
FORCEPROP 1 LASTPIN (-3275 5125) $PN 1
J 0
(-3265 5105);
DISPLAY 0.787234 (-3265 5105);
PAINT MONO (-3265 5105);
FORCEPROP 1 LASTPIN (-3275 4925) $PN 2
J 0
(-3265 4905);
DISPLAY 0.787234 (-3265 4905);
PAINT MONO (-3265 4905);
FORCEPROP 1 LAST PATH I47
J 0
(-3225 5175);
DISPLAY 0.978723 (-3225 5175);
PAINT WHITE (-3225 5175);
DISPLAY INVISIBLE (-3225 5175);
FORCEPROP 2 LAST CDS_LIB pure_quanta
J 0
(-3275 5025);
DISPLAY INVISIBLE (-3275 5025);
FORCEPROP 0 LAST CDS_LOCATION C2374
J 0
(-3225 5175);
DISPLAY 1.021277 (-3225 5175);
DISPLAY INVISIBLE (-3225 5175);
FORCEPROP 0 LAST $SEC 1
J 0
(-3225 5175);
DISPLAY 0.680851 (-3225 5175);
PAINT MONO (-3225 5175);
DISPLAY INVISIBLE (-3225 5175);
FORCEPROP 0 LAST CDS_SEC 1
J 0
(-3225 5175);
DISPLAY 1.021277 (-3225 5175);
DISPLAY INVISIBLE (-3225 5175);
FORCEADD UNIVERSAL_GND..1
(-3275 4825);
FORCEPROP 3 LASTPIN (-3275 4875) SIG_NAME GND\g
J 0
(-3265 4885);
DISPLAY 0.659574 (-3265 4885);
PAINT MONO (-3265 4885);
DISPLAY INVISIBLE (-3265 4885);
FORCEPROP 1 LAST PATH I48
J 0
(-3200 4825);
DISPLAY 0.872340 (-3200 4825);
PAINT AQUA (-3200 4825);
DISPLAY INVISIBLE (-3200 4825);
FORCEPROP 1 LAST HDL_POWER GND
J 1
(-3250 4750);
DISPLAY 0.872340 (-3250 4750);
PAINT GREEN (-3250 4750);
DISPLAY INVISIBLE (-3250 4750);
FORCEPROP 2 LAST CDS_LIB logical_power
J 0
(-3275 4825);
DISPLAY INVISIBLE (-3275 4825);
FORCEADD UNIVERSAL_POWER..1
(-4050 5725);
FORCEPROP 3 LASTPIN (-4050 5675) SIG_NAME P3V3_AUX\g
J 0
(-4040 5685);
DISPLAY 0.659574 (-4040 5685);
PAINT MONO (-4040 5685);
DISPLAY INVISIBLE (-4040 5685);
FORCEPROP 1 LAST HDL_POWER P3V3_AUX
J 1
(-4050 5775);
DISPLAY 0.872340 (-4050 5775);
PAINT GREEN (-4050 5775);
FORCEPROP 1 LAST PATH I49
J 0
(-4000 5750);
DISPLAY 0.872340 (-4000 5750);
PAINT AQUA (-4000 5750);
DISPLAY INVISIBLE (-4000 5750);
FORCEPROP 2 LAST CDS_LIB logical_power
J 0
(-4050 5725);
PAINT MONO (-4050 5725);
DISPLAY INVISIBLE (-4050 5725);
FORCEADD Q_RES..1
(525 3450);
FORCEPROP 1 LAST PART_NUMBER CS00002JB13
J 0
(400 3400);
DISPLAY 0.638298 (400 3400);
DISPLAY INVISIBLE (400 3400);
FORCEPROP 1 LAST WATTAGE 1/16W
J 2
(1125 3450);
DISPLAY 0.638298 (1125 3450);
FORCEPROP 1 LAST MATERIAL CHIP
J 0
(825 3450);
DISPLAY 0.638298 (825 3450);
FORCEPROP 1 LAST PACK_TYPE 0402LF
J 0
(50 3450);
DISPLAY 0.638298 (50 3450);
FORCEPROP 1 LAST VALUE 0
J 2
(725 3450);
DISPLAY 0.638298 (725 3450);
FORCEPROP 1 LAST TOLERANCE 5%
J 0
(750 3450);
DISPLAY 0.638298 (750 3450);
FORCEPROP 1 LAST $LOCATION R3443
J 0
(325 3450);
DISPLAY 0.638298 (325 3450);
FORCEPROP 1 LASTPIN (425 3450) $PN 1
J 0
(437 3462);
DISPLAY 0.787234 (437 3462);
PAINT MONO (437 3462);
FORCEPROP 1 LASTPIN (625 3450) $PN 2
J 0
(587 3462);
DISPLAY 0.787234 (587 3462);
PAINT MONO (587 3462);
FORCEPROP 2 LAST CDS_LIB pure_quanta
J 0
(525 3450);
DISPLAY INVISIBLE (525 3450);
FORCEPROP 1 LAST PATH I5
J 0
(475 3600);
DISPLAY 0.978723 (475 3600);
PAINT WHITE (475 3600);
DISPLAY INVISIBLE (475 3600);
FORCEPROP 0 LAST CDS_LOCATION R3443
J 0
(1125 3500);
DISPLAY 1.021277 (1125 3500);
DISPLAY INVISIBLE (1125 3500);
FORCEPROP 0 LAST $SEC 1
J 0
(1125 3500);
DISPLAY 0.680851 (1125 3500);
PAINT MONO (1125 3500);
DISPLAY INVISIBLE (1125 3500);
FORCEPROP 0 LAST CDS_SEC 1
J 0
(1125 3500);
DISPLAY 1.021277 (1125 3500);
DISPLAY INVISIBLE (1125 3500);
FORCEADD Q_RES..2
(-4050 5500);
FORCEPROP 1 LAST PART_NUMBER CS24702JB10
J 0
(-4010 5325);
DISPLAY 0.638298 (-4010 5325);
DISPLAY INVISIBLE (-4010 5325);
FORCEPROP 1 LAST VALUE 4.7K
J 0
(-4005 5575);
DISPLAY 0.638298 (-4005 5575);
FORCEPROP 1 LAST TOLERANCE 5%
J 0
(-4005 5525);
DISPLAY 0.638298 (-4005 5525);
FORCEPROP 1 LAST MATERIAL CHIP
J 0
(-4010 5425);
DISPLAY 0.638298 (-4010 5425);
FORCEPROP 1 LAST PACK_TYPE 0402LF
J 0
(-4010 5375);
DISPLAY 0.638298 (-4010 5375);
FORCEPROP 1 LAST WATTAGE 1/16W
J 0
(-4010 5475);
DISPLAY 0.638298 (-4010 5475);
FORCEPROP 1 LAST $LOCATION R4740
J 0
(-4005 5625);
DISPLAY 0.638298 (-4005 5625);
FORCEPROP 1 LASTPIN (-4050 5600) $PN 1
J 0
(-4045 5562);
DISPLAY 0.787234 (-4045 5562);
FORCEPROP 1 LASTPIN (-4050 5400) $PN 2
J 0
(-4045 5410);
DISPLAY 0.787234 (-4045 5410);
FORCEPROP 1 LAST PATH I50
J 0
(-4000 5675);
DISPLAY 0.978723 (-4000 5675);
PAINT WHITE (-4000 5675);
DISPLAY INVISIBLE (-4000 5675);
FORCEPROP 2 LAST CDS_LIB pure_quanta
J 0
(-4050 5500);
PAINT MONO (-4050 5500);
DISPLAY INVISIBLE (-4050 5500);
FORCEPROP 2 LAST CDS_LOCATION R4740
J 0
(-4000 5725);
DISPLAY 1.021277 (-4000 5725);
DISPLAY INVISIBLE (-4000 5725);
FORCEPROP 2 LAST $SEC 1
J 0
(-4000 5725);
DISPLAY 0.680851 (-4000 5725);
PAINT MONO (-4000 5725);
DISPLAY INVISIBLE (-4000 5725);
FORCEPROP 2 LAST CDS_SEC 1
J 0
(-4000 5725);
DISPLAY 1.021277 (-4000 5725);
DISPLAY INVISIBLE (-4000 5725);
FORCEADD MOSFET_NCH_DUAL..2
(-4100 5075);
FORCEPROP 1 LAST PART_NUMBER BAM138K0003
J 0
(-3949 4981);
DISPLAY 0.723404 (-3949 4981);
PAINT GREEN (-3949 4981);
DISPLAY INVISIBLE (-3949 4981);
FORCEPROP 1 LAST MATERIAL IC
J 0
(-3949 4926);
DISPLAY 0.723404 (-3949 4926);
PAINT GREEN (-3949 4926);
FORCEPROP 2 LAST PART_TYPE SMLF
J 0
(-3925 5150);
DISPLAY 1.021277 (-3925 5150);
FORCEPROP 2 LAST VALUE PJT138K
J 0
(-3925 5100);
DISPLAY 1.021277 (-3925 5100);
FORCEPROP 1 LAST LOCATION Q153
J 0
(-3949 5051);
DISPLAY 0.723404 (-3949 5051);
PAINT GREEN (-3949 5051);
FORCEPROP 0 LASTPIN (-4050 5275) $PN 3
R 1
J 0
(-4060 5285);
DISPLAY 0.680851 (-4060 5285);
PAINT MONO (-4060 5285);
FORCEPROP 0 LASTPIN (-4300 5025) $PN 5
J 2
(-4310 5035);
DISPLAY 0.680851 (-4310 5035);
PAINT MONO (-4310 5035);
FORCEPROP 0 LASTPIN (-4050 4875) $PN 4
R 1
J 2
(-4060 4865);
DISPLAY 0.680851 (-4060 4865);
PAINT MONO (-4060 4865);
FORCEPROP 1 LAST PATH I51
J 0
(-3950 4925);
DISPLAY 0.723404 (-3950 4925);
PAINT GREEN (-3950 4925);
DISPLAY INVISIBLE (-3950 4925);
FORCEPROP 2 LAST CDS_LIB pure_quanta
J 0
(-4100 5075);
DISPLAY INVISIBLE (-4100 5075);
FORCEPROP 1 LAST NEEDS_NO_SIZE TRUE
J 0
(-3950 4966);
DISPLAY 0.468085 (-3950 4966);
PAINT GREEN (-3950 4966);
DISPLAY INVISIBLE (-3950 4966);
FORCEPROP 1 LAST CDS_LMAN_SYM_OUTLINE -150,150,150,-150
J 0
(-4100 5075);
DISPLAY 0.468085 (-4100 5075);
PAINT GREEN (-4100 5075);
DISPLAY INVISIBLE (-4100 5075);
FORCEPROP 0 LAST $SEC 2
J 0
(-3925 5200);
DISPLAY 0.680851 (-3925 5200);
PAINT MONO (-3925 5200);
DISPLAY INVISIBLE (-3925 5200);
FORCEPROP 0 LAST CDS_SEC 2
J 0
(-3925 5200);
DISPLAY 1.021277 (-3925 5200);
DISPLAY INVISIBLE (-3925 5200);
FORCEADD UNIVERSAL_GND..1
(-4050 4700);
FORCEPROP 3 LASTPIN (-4050 4750) SIG_NAME GND\g
J 0
(-4040 4760);
DISPLAY 0.659574 (-4040 4760);
PAINT MONO (-4040 4760);
DISPLAY INVISIBLE (-4040 4760);
FORCEPROP 1 LAST PATH I52
J 0
(-3975 4700);
DISPLAY 0.872340 (-3975 4700);
PAINT AQUA (-3975 4700);
DISPLAY INVISIBLE (-3975 4700);
FORCEPROP 1 LAST HDL_POWER GND
J 1
(-4025 4625);
DISPLAY 0.872340 (-4025 4625);
PAINT GREEN (-4025 4625);
DISPLAY INVISIBLE (-4025 4625);
FORCEPROP 2 LAST CDS_LIB logical_power
J 0
(-4050 4700);
DISPLAY INVISIBLE (-4050 4700);
FORCEADD UNIVERSAL_POWER..1
(-5200 5600);
FORCEPROP 3 LASTPIN (-5200 5550) SIG_NAME P3V3_AUX\g
J 0
(-5190 5560);
DISPLAY 0.659574 (-5190 5560);
PAINT MONO (-5190 5560);
DISPLAY INVISIBLE (-5190 5560);
FORCEPROP 1 LAST HDL_POWER P3V3_AUX
J 1
(-5200 5650);
DISPLAY 0.872340 (-5200 5650);
PAINT GREEN (-5200 5650);
FORCEPROP 1 LAST PATH I53
J 0
(-5150 5625);
DISPLAY 0.872340 (-5150 5625);
PAINT AQUA (-5150 5625);
DISPLAY INVISIBLE (-5150 5625);
FORCEPROP 2 LAST CDS_LIB logical_power
J 0
(-5200 5600);
PAINT MONO (-5200 5600);
DISPLAY INVISIBLE (-5200 5600);
FORCEADD Q_RES..2
(-5200 5375);
FORCEPROP 1 LAST PART_NUMBER CS24702JB10
J 0
(-5160 5200);
DISPLAY 0.638298 (-5160 5200);
DISPLAY INVISIBLE (-5160 5200);
FORCEPROP 1 LAST WATTAGE 1/16W
J 0
(-5160 5350);
DISPLAY 0.638298 (-5160 5350);
FORCEPROP 1 LAST VALUE 4.7K
J 0
(-5155 5450);
DISPLAY 0.638298 (-5155 5450);
FORCEPROP 1 LAST MATERIAL CHIP
J 0
(-5160 5300);
DISPLAY 0.638298 (-5160 5300);
FORCEPROP 1 LAST TOLERANCE 5%
J 0
(-5155 5400);
DISPLAY 0.638298 (-5155 5400);
FORCEPROP 1 LAST PACK_TYPE 0402LF
J 0
(-5160 5250);
DISPLAY 0.638298 (-5160 5250);
FORCEPROP 1 LAST $LOCATION R4739
J 0
(-5155 5500);
DISPLAY 0.638298 (-5155 5500);
FORCEPROP 1 LASTPIN (-5200 5475) $PN 1
J 0
(-5195 5437);
DISPLAY 0.787234 (-5195 5437);
FORCEPROP 1 LASTPIN (-5200 5275) $PN 2
J 0
(-5195 5285);
DISPLAY 0.787234 (-5195 5285);
FORCEPROP 1 LAST PATH I54
J 0
(-5150 5550);
DISPLAY 0.978723 (-5150 5550);
PAINT WHITE (-5150 5550);
DISPLAY INVISIBLE (-5150 5550);
FORCEPROP 2 LAST CDS_LIB pure_quanta
J 0
(-5200 5375);
PAINT MONO (-5200 5375);
DISPLAY INVISIBLE (-5200 5375);
FORCEPROP 2 LAST CDS_LOCATION R4739
J 0
(-5150 5600);
DISPLAY 1.021277 (-5150 5600);
DISPLAY INVISIBLE (-5150 5600);
FORCEPROP 2 LAST $SEC 1
J 0
(-5150 5600);
DISPLAY 0.680851 (-5150 5600);
PAINT MONO (-5150 5600);
DISPLAY INVISIBLE (-5150 5600);
FORCEPROP 2 LAST CDS_SEC 1
J 0
(-5150 5600);
DISPLAY 1.021277 (-5150 5600);
DISPLAY INVISIBLE (-5150 5600);
FORCEADD MOSFET_NCH_DUAL..1
(-5250 4775);
FORCEPROP 1 LAST PART_NUMBER BAM138K0003
J 0
(-5099 4689);
DISPLAY 0.723404 (-5099 4689);
PAINT GREEN (-5099 4689);
DISPLAY INVISIBLE (-5099 4689);
FORCEPROP 1 LAST MATERIAL IC
J 0
(-5099 4624);
DISPLAY 0.723404 (-5099 4624);
PAINT GREEN (-5099 4624);
FORCEPROP 2 LAST PART_TYPE SMLF
J 0
(-5075 4850);
DISPLAY 1.021277 (-5075 4850);
FORCEPROP 2 LAST VALUE PJT138K
J 0
(-5075 4800);
DISPLAY 1.021277 (-5075 4800);
FORCEPROP 1 LAST LOCATION Q153
J 0
(-5099 4749);
DISPLAY 0.723404 (-5099 4749);
PAINT GREEN (-5099 4749);
FORCEPROP 0 LASTPIN (-5200 4975) $PN 6
R 1
J 0
(-5210 4985);
DISPLAY 0.680851 (-5210 4985);
PAINT MONO (-5210 4985);
FORCEPROP 0 LASTPIN (-5450 4725) $PN 2
J 2
(-5460 4735);
DISPLAY 0.680851 (-5460 4735);
PAINT MONO (-5460 4735);
FORCEPROP 0 LASTPIN (-5200 4575) $PN 1
R 1
J 2
(-5210 4565);
DISPLAY 0.680851 (-5210 4565);
PAINT MONO (-5210 4565);
FORCEPROP 1 LAST PATH I55
J 0
(-5250 4775);
DISPLAY 0.723404 (-5250 4775);
PAINT GREEN (-5250 4775);
DISPLAY INVISIBLE (-5250 4775);
FORCEPROP 1 LAST CDS_LMAN_SYM_OUTLINE -150,150,150,-150
J 0
(-5250 4775);
DISPLAY 0.468085 (-5250 4775);
PAINT GREEN (-5250 4775);
DISPLAY INVISIBLE (-5250 4775);
FORCEPROP 1 LAST NEEDS_NO_SIZE TRUE
J 0
(-5250 4774);
DISPLAY 0.468085 (-5250 4774);
PAINT GREEN (-5250 4774);
DISPLAY INVISIBLE (-5250 4774);
FORCEPROP 2 LAST CDS_LIB pure_quanta
J 0
(-5250 4775);
DISPLAY INVISIBLE (-5250 4775);
FORCEPROP 0 LAST $SEC 1
J 0
(-5075 4900);
DISPLAY 0.680851 (-5075 4900);
PAINT MONO (-5075 4900);
DISPLAY INVISIBLE (-5075 4900);
FORCEPROP 2 LAST CDS_SEC 1
J 0
(-5075 4900);
DISPLAY 1.021277 (-5075 4900);
DISPLAY INVISIBLE (-5075 4900);
FORCEADD UNIVERSAL_GND..1
(-5200 4400);
FORCEPROP 3 LASTPIN (-5200 4450) SIG_NAME GND\g
J 0
(-5190 4460);
DISPLAY 0.659574 (-5190 4460);
PAINT MONO (-5190 4460);
DISPLAY INVISIBLE (-5190 4460);
FORCEPROP 1 LAST PATH I56
J 0
(-5125 4400);
DISPLAY 0.872340 (-5125 4400);
PAINT AQUA (-5125 4400);
DISPLAY INVISIBLE (-5125 4400);
FORCEPROP 2 LAST CDS_LIB logical_power
J 0
(-5200 4400);
DISPLAY INVISIBLE (-5200 4400);
FORCEPROP 1 LAST HDL_POWER GND
J 1
(-5175 4325);
DISPLAY 0.872340 (-5175 4325);
PAINT GREEN (-5175 4325);
DISPLAY INVISIBLE (-5175 4325);
FORCEADD UNIVERSAL_POWER..1
(-6375 5250);
FORCEPROP 3 LASTPIN (-6375 5200) SIG_NAME P3V3_AUX\g
J 0
(-6365 5210);
DISPLAY 0.659574 (-6365 5210);
PAINT MONO (-6365 5210);
DISPLAY INVISIBLE (-6365 5210);
FORCEPROP 1 LAST HDL_POWER P3V3_AUX
J 1
(-6375 5300);
DISPLAY 0.872340 (-6375 5300);
PAINT GREEN (-6375 5300);
FORCEPROP 1 LAST PATH I57
J 0
(-6325 5275);
DISPLAY 0.872340 (-6325 5275);
PAINT AQUA (-6325 5275);
DISPLAY INVISIBLE (-6325 5275);
FORCEPROP 2 LAST CDS_LIB logical_power
J 0
(-6375 5250);
PAINT MONO (-6375 5250);
DISPLAY INVISIBLE (-6375 5250);
FORCEADD Q_RES..2
(-6375 5000);
FORCEPROP 1 LAST PART_NUMBER CS31002FB08
J 0
(-6335 4875);
DISPLAY 0.510638 (-6335 4875);
DISPLAY INVISIBLE (-6335 4875);
FORCEPROP 1 LAST TOLERANCE 1%
J 0
(-6330 5025);
DISPLAY 0.510638 (-6330 5025);
FORCEPROP 1 LAST WATTAGE 1/16W
J 0
(-6335 4975);
DISPLAY 0.510638 (-6335 4975);
FORCEPROP 1 LAST VALUE 10K
J 0
(-6330 5075);
DISPLAY 0.510638 (-6330 5075);
FORCEPROP 1 LAST MATERIAL CHIP
J 0
(-6335 4925);
DISPLAY 0.510638 (-6335 4925);
FORCEPROP 1 LAST PACK_TYPE 0402LF
J 0
(-6335 4825);
DISPLAY 0.510638 (-6335 4825);
FORCEPROP 1 LAST $LOCATION R4737
J 0
(-6330 5125);
DISPLAY 0.978723 (-6330 5125);
FORCEPROP 1 LASTPIN (-6375 5100) $PN 1
J 0
(-6370 5062);
DISPLAY 0.787234 (-6370 5062);
PAINT MONO (-6370 5062);
FORCEPROP 1 LASTPIN (-6375 4900) $PN 2
J 0
(-6370 4910);
DISPLAY 0.787234 (-6370 4910);
PAINT MONO (-6370 4910);
FORCEPROP 1 LAST PATH I58
J 0
(-6325 5175);
DISPLAY 0.978723 (-6325 5175);
PAINT WHITE (-6325 5175);
DISPLAY INVISIBLE (-6325 5175);
FORCEPROP 2 LAST CDS_LIB pure_quanta
J 0
(-6375 5000);
DISPLAY INVISIBLE (-6375 5000);
FORCEPROP 0 LAST CDS_LOCATION R4737
J 0
(-6325 5175);
DISPLAY 1.021277 (-6325 5175);
DISPLAY INVISIBLE (-6325 5175);
FORCEPROP 0 LAST $SEC 1
J 0
(-6325 5175);
DISPLAY 0.680851 (-6325 5175);
PAINT MONO (-6325 5175);
DISPLAY INVISIBLE (-6325 5175);
FORCEPROP 0 LAST CDS_SEC 1
J 0
(-6325 5175);
DISPLAY 1.021277 (-6325 5175);
DISPLAY INVISIBLE (-6325 5175);
FORCEADD OFFPAGE..4
R 2
(-6625 4725);
FORCEPROP 2 LAST $XR0 137 
J 0
(-6907 4725);
DISPLAY 0.638298 (-6907 4725);
PAINT MONO (-6907 4725);
FORCEPROP 2 LAST PATH I59
J 0
(-6875 4775);
DISPLAY 1.021277 (-6875 4775);
DISPLAY INVISIBLE (-6875 4775);
FORCEPROP 1 LAST OFFPAGE TRUE
J 2
(-6950 4600);
DISPLAY 0.872340 (-6950 4600);
PAINT GREEN (-6950 4600);
DISPLAY INVISIBLE (-6950 4600);
FORCEPROP 1 LAST COMMENT_BODY TRUE
J 2
(-6600 4625);
DISPLAY 0.872340 (-6600 4625);
PAINT GREEN (-6600 4625);
DISPLAY INVISIBLE (-6600 4625);
FORCEPROP 2 LAST CDS_LIB standard
J 0
(-6625 4725);
DISPLAY INVISIBLE (-6625 4725);
FORCEADD Q_RES..1
(525 3650);
FORCEPROP 1 LAST PART_NUMBER CS00002JB13
J 0
(400 3600);
DISPLAY 0.638298 (400 3600);
DISPLAY INVISIBLE (400 3600);
FORCEPROP 1 LAST PACK_TYPE 0402LF
J 0
(50 3650);
DISPLAY 0.638298 (50 3650);
FORCEPROP 1 LAST VALUE 0
J 2
(725 3650);
DISPLAY 0.638298 (725 3650);
FORCEPROP 1 LAST MATERIAL CHIP
J 0
(825 3650);
DISPLAY 0.638298 (825 3650);
FORCEPROP 1 LAST TOLERANCE 5%
J 0
(750 3650);
DISPLAY 0.638298 (750 3650);
FORCEPROP 1 LAST WATTAGE 1/16W
J 2
(1125 3650);
DISPLAY 0.638298 (1125 3650);
FORCEPROP 1 LAST $LOCATION R3442
J 0
(325 3650);
DISPLAY 0.638298 (325 3650);
FORCEPROP 1 LASTPIN (425 3650) $PN 1
J 0
(437 3662);
DISPLAY 0.787234 (437 3662);
PAINT MONO (437 3662);
FORCEPROP 1 LASTPIN (625 3650) $PN 2
J 0
(587 3662);
DISPLAY 0.787234 (587 3662);
PAINT MONO (587 3662);
FORCEPROP 2 LAST CDS_LIB pure_quanta
J 0
(525 3650);
DISPLAY INVISIBLE (525 3650);
FORCEPROP 1 LAST PATH I6
J 0
(475 3800);
DISPLAY 0.978723 (475 3800);
PAINT WHITE (475 3800);
DISPLAY INVISIBLE (475 3800);
FORCEPROP 0 LAST CDS_LOCATION R3442
J 0
(1125 3700);
DISPLAY 1.021277 (1125 3700);
DISPLAY INVISIBLE (1125 3700);
FORCEPROP 0 LAST $SEC 1
J 0
(1125 3700);
DISPLAY 0.680851 (1125 3700);
PAINT MONO (1125 3700);
DISPLAY INVISIBLE (1125 3700);
FORCEPROP 0 LAST CDS_SEC 1
J 0
(1125 3700);
DISPLAY 1.021277 (1125 3700);
DISPLAY INVISIBLE (1125 3700);
FORCEADD Q_RES..2
(-6350 4525);
FORCEPROP 1 LAST PART_NUMBER CS41002FB09
J 0
(-6310 4400);
DISPLAY 0.510638 (-6310 4400);
DISPLAY INVISIBLE (-6310 4400);
FORCEPROP 1 LAST MATERIAL EMPTY
J 0
(-6310 4450);
DISPLAY 0.510638 (-6310 4450);
PAINT RED (-6310 4450);
FORCEPROP 1 LAST PACK_TYPE 0402LF
J 0
(-6310 4350);
DISPLAY 0.510638 (-6310 4350);
FORCEPROP 1 LAST WATTAGE 1/16W
J 0
(-6310 4500);
DISPLAY 0.510638 (-6310 4500);
FORCEPROP 1 LAST TOLERANCE 1%
J 0
(-6305 4550);
DISPLAY 0.510638 (-6305 4550);
FORCEPROP 1 LAST VALUE 100K
J 0
(-6305 4600);
DISPLAY 0.510638 (-6305 4600);
FORCEPROP 1 LAST $LOCATION R4738
J 0
(-6305 4650);
DISPLAY 0.978723 (-6305 4650);
FORCEPROP 1 LASTPIN (-6350 4625) $PN 1
J 0
(-6345 4587);
DISPLAY 0.787234 (-6345 4587);
PAINT MONO (-6345 4587);
FORCEPROP 1 LASTPIN (-6350 4425) $PN 2
J 0
(-6345 4435);
DISPLAY 0.787234 (-6345 4435);
PAINT MONO (-6345 4435);
FORCEPROP 1 LAST PATH I60
J 0
(-6300 4700);
DISPLAY 0.978723 (-6300 4700);
PAINT WHITE (-6300 4700);
DISPLAY INVISIBLE (-6300 4700);
FORCEPROP 2 LAST CDS_LIB pure_quanta
J 0
(-6350 4525);
DISPLAY INVISIBLE (-6350 4525);
FORCEPROP 0 LAST CDS_LOCATION R4738
J 0
(-6300 4700);
DISPLAY 1.021277 (-6300 4700);
DISPLAY INVISIBLE (-6300 4700);
FORCEPROP 0 LAST $SEC 1
J 0
(-6300 4700);
DISPLAY 0.680851 (-6300 4700);
PAINT MONO (-6300 4700);
DISPLAY INVISIBLE (-6300 4700);
FORCEPROP 0 LAST CDS_SEC 1
J 0
(-6300 4700);
DISPLAY 1.021277 (-6300 4700);
DISPLAY INVISIBLE (-6300 4700);
FORCEADD UNIVERSAL_GND..1
(-6350 4250);
FORCEPROP 3 LASTPIN (-6350 4300) SIG_NAME GND\g
J 0
(-6340 4310);
DISPLAY 0.659574 (-6340 4310);
PAINT MONO (-6340 4310);
DISPLAY INVISIBLE (-6340 4310);
FORCEPROP 1 LAST PATH I61
J 0
(-6275 4250);
DISPLAY 0.872340 (-6275 4250);
PAINT AQUA (-6275 4250);
DISPLAY INVISIBLE (-6275 4250);
FORCEPROP 1 LAST HDL_POWER GND
J 1
(-6325 4175);
DISPLAY 0.872340 (-6325 4175);
PAINT GREEN (-6325 4175);
DISPLAY INVISIBLE (-6325 4175);
FORCEPROP 2 LAST CDS_LIB logical_power
J 0
(-6350 4250);
DISPLAY INVISIBLE (-6350 4250);
FORCEADD MOSFET_NCH_DUAL..2
(-4075 3675);
FORCEPROP 1 LAST PART_NUMBER BAM138K0003
J 0
(-3924 3581);
DISPLAY 0.723404 (-3924 3581);
PAINT GREEN (-3924 3581);
DISPLAY INVISIBLE (-3924 3581);
FORCEPROP 1 LAST MATERIAL IC
J 0
(-3924 3526);
DISPLAY 0.723404 (-3924 3526);
PAINT GREEN (-3924 3526);
FORCEPROP 2 LAST VALUE PJT138K
J 0
(-3900 3700);
DISPLAY 1.021277 (-3900 3700);
FORCEPROP 2 LAST PART_TYPE SMLF
J 0
(-3900 3750);
DISPLAY 1.021277 (-3900 3750);
FORCEPROP 1 LAST LOCATION Q154
J 0
(-3924 3651);
DISPLAY 0.723404 (-3924 3651);
PAINT GREEN (-3924 3651);
FORCEPROP 0 LASTPIN (-4025 3875) $PN 3
R 1
J 0
(-4035 3885);
DISPLAY 0.680851 (-4035 3885);
PAINT MONO (-4035 3885);
FORCEPROP 0 LASTPIN (-4275 3625) $PN 5
J 2
(-4285 3635);
DISPLAY 0.680851 (-4285 3635);
PAINT MONO (-4285 3635);
FORCEPROP 0 LASTPIN (-4025 3475) $PN 4
R 1
J 2
(-4035 3465);
DISPLAY 0.680851 (-4035 3465);
PAINT MONO (-4035 3465);
FORCEPROP 1 LAST CDS_LMAN_SYM_OUTLINE -150,150,150,-150
J 0
(-4075 3675);
DISPLAY 0.468085 (-4075 3675);
PAINT GREEN (-4075 3675);
DISPLAY INVISIBLE (-4075 3675);
FORCEPROP 1 LAST NEEDS_NO_SIZE TRUE
J 0
(-3925 3566);
DISPLAY 0.468085 (-3925 3566);
PAINT GREEN (-3925 3566);
DISPLAY INVISIBLE (-3925 3566);
FORCEPROP 2 LAST CDS_LIB pure_quanta
J 0
(-4075 3675);
DISPLAY INVISIBLE (-4075 3675);
FORCEPROP 1 LAST PATH I62
J 0
(-3925 3525);
DISPLAY 0.723404 (-3925 3525);
PAINT GREEN (-3925 3525);
DISPLAY INVISIBLE (-3925 3525);
FORCEPROP 0 LAST $SEC 2
J 0
(-3900 3800);
DISPLAY 0.680851 (-3900 3800);
PAINT MONO (-3900 3800);
DISPLAY INVISIBLE (-3900 3800);
FORCEPROP 0 LAST CDS_SEC 2
J 0
(-3900 3800);
DISPLAY 1.021277 (-3900 3800);
DISPLAY INVISIBLE (-3900 3800);
FORCEADD OFFPAGE..2
(-2900 3925);
FORCEPROP 2 LAST $XR0 227 
J 0
(-2711 3925);
DISPLAY 0.638298 (-2711 3925);
PAINT MONO (-2711 3925);
FORCEPROP 2 LAST CDS_LIB standard
J 0
(-2900 3925);
DISPLAY INVISIBLE (-2900 3925);
FORCEPROP 1 LAST COMMENT_BODY TRUE
J 0
(-2945 3830);
DISPLAY 0.872340 (-2945 3830);
PAINT GREEN (-2945 3830);
DISPLAY INVISIBLE (-2945 3830);
FORCEPROP 1 LAST OFFPAGE TRUE
J 0
(-2575 3800);
DISPLAY 0.872340 (-2575 3800);
PAINT AQUA (-2575 3800);
DISPLAY INVISIBLE (-2575 3800);
FORCEPROP 2 LAST PATH I63
J 0
(-2700 3975);
DISPLAY 1.021277 (-2700 3975);
DISPLAY INVISIBLE (-2700 3975);
FORCEADD UNIVERSAL_POWER..1
(-4025 4325);
FORCEPROP 3 LASTPIN (-4025 4275) SIG_NAME P3V3_AUX\g
J 0
(-4015 4285);
DISPLAY 0.659574 (-4015 4285);
PAINT MONO (-4015 4285);
DISPLAY INVISIBLE (-4015 4285);
FORCEPROP 1 LAST HDL_POWER P3V3_AUX
J 1
(-4025 4375);
DISPLAY 0.872340 (-4025 4375);
PAINT GREEN (-4025 4375);
FORCEPROP 2 LAST CDS_LIB logical_power
J 0
(-4025 4325);
PAINT MONO (-4025 4325);
DISPLAY INVISIBLE (-4025 4325);
FORCEPROP 1 LAST PATH I64
J 0
(-3975 4350);
DISPLAY 0.872340 (-3975 4350);
PAINT AQUA (-3975 4350);
DISPLAY INVISIBLE (-3975 4350);
FORCEADD Q_RES..2
(-4025 4100);
FORCEPROP 1 LAST PART_NUMBER CS24702JB10
J 0
(-3985 3925);
DISPLAY 0.638298 (-3985 3925);
DISPLAY INVISIBLE (-3985 3925);
FORCEPROP 1 LAST WATTAGE 1/16W
J 0
(-3985 4075);
DISPLAY 0.638298 (-3985 4075);
FORCEPROP 1 LAST TOLERANCE 5%
J 0
(-3980 4125);
DISPLAY 0.638298 (-3980 4125);
FORCEPROP 1 LAST VALUE 4.7K
J 0
(-3980 4175);
DISPLAY 0.638298 (-3980 4175);
FORCEPROP 1 LAST MATERIAL CHIP
J 0
(-3985 4025);
DISPLAY 0.638298 (-3985 4025);
FORCEPROP 1 LAST PACK_TYPE 0402LF
J 0
(-3985 3975);
DISPLAY 0.638298 (-3985 3975);
FORCEPROP 1 LAST $LOCATION R4801
J 0
(-3980 4225);
DISPLAY 0.638298 (-3980 4225);
FORCEPROP 1 LASTPIN (-4025 4200) $PN 1
J 0
(-4020 4162);
DISPLAY 0.787234 (-4020 4162);
FORCEPROP 1 LASTPIN (-4025 4000) $PN 2
J 0
(-4020 4010);
DISPLAY 0.787234 (-4020 4010);
FORCEPROP 2 LAST CDS_LIB pure_quanta
J 0
(-4025 4100);
PAINT MONO (-4025 4100);
DISPLAY INVISIBLE (-4025 4100);
FORCEPROP 1 LAST PATH I65
J 0
(-3975 4275);
DISPLAY 0.978723 (-3975 4275);
PAINT WHITE (-3975 4275);
DISPLAY INVISIBLE (-3975 4275);
FORCEPROP 2 LAST CDS_LOCATION R4801
J 0
(-3975 4325);
DISPLAY 1.021277 (-3975 4325);
DISPLAY INVISIBLE (-3975 4325);
FORCEPROP 2 LAST $SEC 1
J 0
(-3975 4325);
DISPLAY 0.680851 (-3975 4325);
PAINT MONO (-3975 4325);
DISPLAY INVISIBLE (-3975 4325);
FORCEPROP 2 LAST CDS_SEC 1
J 0
(-3975 4325);
DISPLAY 1.021277 (-3975 4325);
DISPLAY INVISIBLE (-3975 4325);
FORCEADD Q_CAP..1
(-3250 3625);
FORCEPROP 1 LAST PART_NUMBER TMP_QCH21006JB10
J 0
(-3200 3475);
DISPLAY 0.638298 (-3200 3475);
DISPLAY INVISIBLE (-3200 3475);
FORCEPROP 1 LAST MATERIAL EMPTY
J 0
(-3200 3525);
DISPLAY 0.638298 (-3200 3525);
PAINT RED (-3200 3525);
FORCEPROP 1 LAST VALUE 1000PF
J 0
(-3200 3675);
DISPLAY 0.638298 (-3200 3675);
FORCEPROP 1 LAST TOLERANCE 5%
J 0
(-3200 3575);
DISPLAY 0.638298 (-3200 3575);
FORCEPROP 1 LAST PACK_TYPE 0402
J 0
(-3200 3425);
DISPLAY 0.638298 (-3200 3425);
FORCEPROP 1 LAST VOLTAGE 50V
J 0
(-3200 3625);
DISPLAY 0.638298 (-3200 3625);
FORCEPROP 1 LAST $LOCATION C2391
J 0
(-3200 3725);
DISPLAY 0.978723 (-3200 3725);
FORCEPROP 1 LASTPIN (-3250 3725) $PN 1
J 0
(-3240 3705);
DISPLAY 0.787234 (-3240 3705);
PAINT MONO (-3240 3705);
FORCEPROP 1 LASTPIN (-3250 3525) $PN 2
J 0
(-3240 3505);
DISPLAY 0.787234 (-3240 3505);
PAINT MONO (-3240 3505);
FORCEPROP 2 LAST CDS_LIB pure_quanta
J 0
(-3250 3625);
DISPLAY INVISIBLE (-3250 3625);
FORCEPROP 1 LAST PATH I66
J 0
(-3200 3775);
DISPLAY 0.978723 (-3200 3775);
PAINT WHITE (-3200 3775);
DISPLAY INVISIBLE (-3200 3775);
FORCEPROP 0 LAST CDS_LOCATION C2391
J 0
(-3200 3775);
DISPLAY 1.021277 (-3200 3775);
DISPLAY INVISIBLE (-3200 3775);
FORCEPROP 0 LAST $SEC 1
J 0
(-3200 3775);
DISPLAY 0.680851 (-3200 3775);
PAINT MONO (-3200 3775);
DISPLAY INVISIBLE (-3200 3775);
FORCEPROP 0 LAST CDS_SEC 1
J 0
(-3200 3775);
DISPLAY 1.021277 (-3200 3775);
DISPLAY INVISIBLE (-3200 3775);
FORCEADD UNIVERSAL_GND..1
(-3250 3425);
FORCEPROP 3 LASTPIN (-3250 3475) SIG_NAME GND\g
J 0
(-3240 3485);
DISPLAY 0.659574 (-3240 3485);
PAINT MONO (-3240 3485);
DISPLAY INVISIBLE (-3240 3485);
FORCEPROP 2 LAST CDS_LIB logical_power
J 0
(-3250 3425);
DISPLAY INVISIBLE (-3250 3425);
FORCEPROP 1 LAST HDL_POWER GND
J 1
(-3225 3350);
DISPLAY 0.872340 (-3225 3350);
PAINT GREEN (-3225 3350);
DISPLAY INVISIBLE (-3225 3350);
FORCEPROP 1 LAST PATH I67
J 0
(-3175 3425);
DISPLAY 0.872340 (-3175 3425);
PAINT AQUA (-3175 3425);
DISPLAY INVISIBLE (-3175 3425);
FORCEADD UNIVERSAL_GND..1
(-4025 3300);
FORCEPROP 3 LASTPIN (-4025 3350) SIG_NAME GND\g
J 0
(-4015 3360);
DISPLAY 0.659574 (-4015 3360);
PAINT MONO (-4015 3360);
DISPLAY INVISIBLE (-4015 3360);
FORCEPROP 2 LAST CDS_LIB logical_power
J 0
(-4025 3300);
DISPLAY INVISIBLE (-4025 3300);
FORCEPROP 1 LAST HDL_POWER GND
J 1
(-4000 3225);
DISPLAY 0.872340 (-4000 3225);
PAINT GREEN (-4000 3225);
DISPLAY INVISIBLE (-4000 3225);
FORCEPROP 1 LAST PATH I68
J 0
(-3950 3300);
DISPLAY 0.872340 (-3950 3300);
PAINT AQUA (-3950 3300);
DISPLAY INVISIBLE (-3950 3300);
FORCEADD UNIVERSAL_POWER..1
(-5175 4200);
FORCEPROP 3 LASTPIN (-5175 4150) SIG_NAME P3V3_AUX\g
J 0
(-5165 4160);
DISPLAY 0.659574 (-5165 4160);
PAINT MONO (-5165 4160);
DISPLAY INVISIBLE (-5165 4160);
FORCEPROP 1 LAST HDL_POWER P3V3_AUX
J 1
(-5175 4250);
DISPLAY 0.872340 (-5175 4250);
PAINT GREEN (-5175 4250);
FORCEPROP 2 LAST CDS_LIB logical_power
J 0
(-5175 4200);
PAINT MONO (-5175 4200);
DISPLAY INVISIBLE (-5175 4200);
FORCEPROP 1 LAST PATH I69
J 0
(-5125 4225);
DISPLAY 0.872340 (-5125 4225);
PAINT AQUA (-5125 4225);
DISPLAY INVISIBLE (-5125 4225);
FORCEADD Q_RES..1
(525 3850);
FORCEPROP 1 LAST PART_NUMBER CS00002JB13
J 0
(400 3800);
DISPLAY 0.638298 (400 3800);
DISPLAY INVISIBLE (400 3800);
FORCEPROP 1 LAST TOLERANCE 5%
J 0
(750 3850);
DISPLAY 0.638298 (750 3850);
FORCEPROP 1 LAST WATTAGE 1/16W
J 2
(1100 3850);
DISPLAY 0.638298 (1100 3850);
FORCEPROP 1 LAST MATERIAL CHIP
J 0
(825 3850);
DISPLAY 0.638298 (825 3850);
FORCEPROP 1 LAST VALUE 0
J 2
(725 3850);
DISPLAY 0.638298 (725 3850);
FORCEPROP 1 LAST PACK_TYPE 0402LF
J 0
(50 3850);
DISPLAY 0.638298 (50 3850);
FORCEPROP 1 LAST $LOCATION R3441
J 0
(325 3850);
DISPLAY 0.638298 (325 3850);
FORCEPROP 1 LASTPIN (425 3850) $PN 1
J 0
(437 3862);
DISPLAY 0.787234 (437 3862);
PAINT MONO (437 3862);
FORCEPROP 1 LASTPIN (625 3850) $PN 2
J 0
(587 3862);
DISPLAY 0.787234 (587 3862);
PAINT MONO (587 3862);
FORCEPROP 2 LAST CDS_LIB pure_quanta
J 0
(525 3850);
DISPLAY INVISIBLE (525 3850);
FORCEPROP 1 LAST PATH I7
J 0
(475 4000);
DISPLAY 0.978723 (475 4000);
PAINT WHITE (475 4000);
DISPLAY INVISIBLE (475 4000);
FORCEPROP 0 LAST CDS_LOCATION R3441
J 0
(475 3950);
DISPLAY 1.021277 (475 3950);
DISPLAY INVISIBLE (475 3950);
FORCEPROP 0 LAST $SEC 1
J 0
(475 3950);
DISPLAY 0.680851 (475 3950);
PAINT MONO (475 3950);
DISPLAY INVISIBLE (475 3950);
FORCEPROP 0 LAST CDS_SEC 1
J 0
(475 3950);
DISPLAY 1.021277 (475 3950);
DISPLAY INVISIBLE (475 3950);
FORCEADD Q_RES..2
(-5175 3975);
FORCEPROP 1 LAST PART_NUMBER CS24702JB10
J 0
(-5135 3800);
DISPLAY 0.638298 (-5135 3800);
DISPLAY INVISIBLE (-5135 3800);
FORCEPROP 1 LAST VALUE 4.7K
J 0
(-5130 4050);
DISPLAY 0.638298 (-5130 4050);
FORCEPROP 1 LAST TOLERANCE 5%
J 0
(-5130 4000);
DISPLAY 0.638298 (-5130 4000);
FORCEPROP 1 LAST PACK_TYPE 0402LF
J 0
(-5135 3850);
DISPLAY 0.638298 (-5135 3850);
FORCEPROP 1 LAST MATERIAL CHIP
J 0
(-5135 3900);
DISPLAY 0.638298 (-5135 3900);
FORCEPROP 1 LAST WATTAGE 1/16W
J 0
(-5135 3950);
DISPLAY 0.638298 (-5135 3950);
FORCEPROP 1 LAST $LOCATION R4800
J 0
(-5130 4100);
DISPLAY 0.638298 (-5130 4100);
FORCEPROP 1 LASTPIN (-5175 4075) $PN 1
J 0
(-5170 4037);
DISPLAY 0.787234 (-5170 4037);
FORCEPROP 1 LASTPIN (-5175 3875) $PN 2
J 0
(-5170 3885);
DISPLAY 0.787234 (-5170 3885);
FORCEPROP 2 LAST CDS_LIB pure_quanta
J 0
(-5175 3975);
PAINT MONO (-5175 3975);
DISPLAY INVISIBLE (-5175 3975);
FORCEPROP 1 LAST PATH I70
J 0
(-5125 4150);
DISPLAY 0.978723 (-5125 4150);
PAINT WHITE (-5125 4150);
DISPLAY INVISIBLE (-5125 4150);
FORCEPROP 2 LAST CDS_LOCATION R4800
J 0
(-5125 4200);
DISPLAY 1.021277 (-5125 4200);
DISPLAY INVISIBLE (-5125 4200);
FORCEPROP 2 LAST $SEC 1
J 0
(-5125 4200);
DISPLAY 0.680851 (-5125 4200);
PAINT MONO (-5125 4200);
DISPLAY INVISIBLE (-5125 4200);
FORCEPROP 2 LAST CDS_SEC 1
J 0
(-5125 4200);
DISPLAY 1.021277 (-5125 4200);
DISPLAY INVISIBLE (-5125 4200);
FORCEADD MOSFET_NCH_DUAL..1
(-5225 3375);
FORCEPROP 1 LAST PART_NUMBER BAM138K0003
J 0
(-5074 3289);
DISPLAY 0.723404 (-5074 3289);
PAINT GREEN (-5074 3289);
DISPLAY INVISIBLE (-5074 3289);
FORCEPROP 2 LAST PART_TYPE SMLF
J 0
(-5050 3450);
DISPLAY 1.021277 (-5050 3450);
FORCEPROP 2 LAST VALUE PJT138K
J 0
(-5050 3400);
DISPLAY 1.021277 (-5050 3400);
FORCEPROP 1 LAST MATERIAL IC
J 0
(-5074 3224);
DISPLAY 0.723404 (-5074 3224);
PAINT GREEN (-5074 3224);
FORCEPROP 1 LAST LOCATION Q154
J 0
(-5074 3349);
DISPLAY 0.723404 (-5074 3349);
PAINT GREEN (-5074 3349);
FORCEPROP 0 LASTPIN (-5175 3575) $PN 6
R 1
J 0
(-5185 3585);
DISPLAY 0.680851 (-5185 3585);
PAINT MONO (-5185 3585);
FORCEPROP 0 LASTPIN (-5425 3325) $PN 2
J 2
(-5435 3335);
DISPLAY 0.680851 (-5435 3335);
PAINT MONO (-5435 3335);
FORCEPROP 0 LASTPIN (-5175 3175) $PN 1
R 1
J 2
(-5185 3165);
DISPLAY 0.680851 (-5185 3165);
PAINT MONO (-5185 3165);
FORCEPROP 2 LAST CDS_LIB pure_quanta
J 0
(-5225 3375);
DISPLAY INVISIBLE (-5225 3375);
FORCEPROP 1 LAST NEEDS_NO_SIZE TRUE
J 0
(-5225 3374);
DISPLAY 0.468085 (-5225 3374);
PAINT GREEN (-5225 3374);
DISPLAY INVISIBLE (-5225 3374);
FORCEPROP 1 LAST CDS_LMAN_SYM_OUTLINE -150,150,150,-150
J 0
(-5225 3375);
DISPLAY 0.468085 (-5225 3375);
PAINT GREEN (-5225 3375);
DISPLAY INVISIBLE (-5225 3375);
FORCEPROP 1 LAST PATH I71
J 0
(-5225 3375);
DISPLAY 0.723404 (-5225 3375);
PAINT GREEN (-5225 3375);
DISPLAY INVISIBLE (-5225 3375);
FORCEPROP 0 LAST $SEC 1
J 0
(-5050 3500);
DISPLAY 0.680851 (-5050 3500);
PAINT MONO (-5050 3500);
DISPLAY INVISIBLE (-5050 3500);
FORCEPROP 2 LAST CDS_SEC 1
J 0
(-5050 3500);
DISPLAY 1.021277 (-5050 3500);
DISPLAY INVISIBLE (-5050 3500);
FORCEADD UNIVERSAL_GND..1
(-5175 3000);
FORCEPROP 3 LASTPIN (-5175 3050) SIG_NAME GND\g
J 0
(-5165 3060);
DISPLAY 0.659574 (-5165 3060);
PAINT MONO (-5165 3060);
DISPLAY INVISIBLE (-5165 3060);
FORCEPROP 1 LAST HDL_POWER GND
J 1
(-5150 2925);
DISPLAY 0.872340 (-5150 2925);
PAINT GREEN (-5150 2925);
DISPLAY INVISIBLE (-5150 2925);
FORCEPROP 2 LAST CDS_LIB logical_power
J 0
(-5175 3000);
DISPLAY INVISIBLE (-5175 3000);
FORCEPROP 1 LAST PATH I72
J 0
(-5100 3000);
DISPLAY 0.872340 (-5100 3000);
PAINT AQUA (-5100 3000);
DISPLAY INVISIBLE (-5100 3000);
FORCEADD UNIVERSAL_POWER..1
(-6350 3850);
FORCEPROP 3 LASTPIN (-6350 3800) SIG_NAME P3V3_AUX\g
J 0
(-6340 3810);
DISPLAY 0.659574 (-6340 3810);
PAINT MONO (-6340 3810);
DISPLAY INVISIBLE (-6340 3810);
FORCEPROP 1 LAST HDL_POWER P3V3_AUX
J 1
(-6350 3900);
DISPLAY 0.872340 (-6350 3900);
PAINT GREEN (-6350 3900);
FORCEPROP 2 LAST CDS_LIB logical_power
J 0
(-6350 3850);
PAINT MONO (-6350 3850);
DISPLAY INVISIBLE (-6350 3850);
FORCEPROP 1 LAST PATH I74
J 0
(-6300 3875);
DISPLAY 0.872340 (-6300 3875);
PAINT AQUA (-6300 3875);
DISPLAY INVISIBLE (-6300 3875);
FORCEADD Q_RES..2
(-6350 3600);
FORCEPROP 1 LAST PART_NUMBER CS31002FB08
J 0
(-6310 3475);
DISPLAY 0.510638 (-6310 3475);
DISPLAY INVISIBLE (-6310 3475);
FORCEPROP 1 LAST PACK_TYPE 0402LF
J 0
(-6310 3425);
DISPLAY 0.510638 (-6310 3425);
FORCEPROP 1 LAST MATERIAL CHIP
J 0
(-6310 3525);
DISPLAY 0.510638 (-6310 3525);
FORCEPROP 1 LAST VALUE 10K
J 0
(-6305 3675);
DISPLAY 0.510638 (-6305 3675);
FORCEPROP 1 LAST TOLERANCE 1%
J 0
(-6305 3625);
DISPLAY 0.510638 (-6305 3625);
FORCEPROP 1 LAST WATTAGE 1/16W
J 0
(-6310 3575);
DISPLAY 0.510638 (-6310 3575);
FORCEPROP 1 LAST $LOCATION R4798
J 0
(-6305 3725);
DISPLAY 0.978723 (-6305 3725);
FORCEPROP 1 LASTPIN (-6350 3700) $PN 1
J 0
(-6345 3662);
DISPLAY 0.787234 (-6345 3662);
PAINT MONO (-6345 3662);
FORCEPROP 1 LASTPIN (-6350 3500) $PN 2
J 0
(-6345 3510);
DISPLAY 0.787234 (-6345 3510);
PAINT MONO (-6345 3510);
FORCEPROP 2 LAST CDS_LIB pure_quanta
J 0
(-6350 3600);
DISPLAY INVISIBLE (-6350 3600);
FORCEPROP 1 LAST PATH I75
J 0
(-6300 3775);
DISPLAY 0.978723 (-6300 3775);
PAINT WHITE (-6300 3775);
DISPLAY INVISIBLE (-6300 3775);
FORCEPROP 0 LAST CDS_LOCATION R4798
J 0
(-6300 3775);
DISPLAY 1.021277 (-6300 3775);
DISPLAY INVISIBLE (-6300 3775);
FORCEPROP 0 LAST $SEC 1
J 0
(-6300 3775);
DISPLAY 0.680851 (-6300 3775);
PAINT MONO (-6300 3775);
DISPLAY INVISIBLE (-6300 3775);
FORCEPROP 0 LAST CDS_SEC 1
J 0
(-6300 3775);
DISPLAY 1.021277 (-6300 3775);
DISPLAY INVISIBLE (-6300 3775);
FORCEADD Q_RES..2
(-6325 3125);
FORCEPROP 1 LAST PART_NUMBER CS41002FB09
J 0
(-6285 3000);
DISPLAY 0.510638 (-6285 3000);
DISPLAY INVISIBLE (-6285 3000);
FORCEPROP 1 LAST TOLERANCE 1%
J 0
(-6280 3150);
DISPLAY 0.510638 (-6280 3150);
FORCEPROP 1 LAST WATTAGE 1/16W
J 0
(-6285 3100);
DISPLAY 0.510638 (-6285 3100);
FORCEPROP 1 LAST PACK_TYPE 0402LF
J 0
(-6285 2950);
DISPLAY 0.510638 (-6285 2950);
FORCEPROP 1 LAST MATERIAL EMPTY
J 0
(-6285 3050);
DISPLAY 0.510638 (-6285 3050);
PAINT RED (-6285 3050);
FORCEPROP 1 LAST VALUE 100K
J 0
(-6280 3200);
DISPLAY 0.510638 (-6280 3200);
FORCEPROP 1 LAST $LOCATION R4799
J 0
(-6280 3250);
DISPLAY 0.978723 (-6280 3250);
FORCEPROP 1 LASTPIN (-6325 3225) $PN 1
J 0
(-6320 3187);
DISPLAY 0.787234 (-6320 3187);
PAINT MONO (-6320 3187);
FORCEPROP 1 LASTPIN (-6325 3025) $PN 2
J 0
(-6320 3035);
DISPLAY 0.787234 (-6320 3035);
PAINT MONO (-6320 3035);
FORCEPROP 2 LAST CDS_LIB pure_quanta
J 0
(-6325 3125);
DISPLAY INVISIBLE (-6325 3125);
FORCEPROP 1 LAST PATH I76
J 0
(-6275 3300);
DISPLAY 0.978723 (-6275 3300);
PAINT WHITE (-6275 3300);
DISPLAY INVISIBLE (-6275 3300);
FORCEPROP 0 LAST CDS_LOCATION R4799
J 0
(-6275 3300);
DISPLAY 1.021277 (-6275 3300);
DISPLAY INVISIBLE (-6275 3300);
FORCEPROP 0 LAST $SEC 1
J 0
(-6275 3300);
DISPLAY 0.680851 (-6275 3300);
PAINT MONO (-6275 3300);
DISPLAY INVISIBLE (-6275 3300);
FORCEPROP 0 LAST CDS_SEC 1
J 0
(-6275 3300);
DISPLAY 1.021277 (-6275 3300);
DISPLAY INVISIBLE (-6275 3300);
FORCEADD UNIVERSAL_GND..1
(-6325 2850);
FORCEPROP 3 LASTPIN (-6325 2900) SIG_NAME GND\g
J 0
(-6315 2910);
DISPLAY 0.659574 (-6315 2910);
PAINT MONO (-6315 2910);
DISPLAY INVISIBLE (-6315 2910);
FORCEPROP 2 LAST CDS_LIB logical_power
J 0
(-6325 2850);
DISPLAY INVISIBLE (-6325 2850);
FORCEPROP 1 LAST HDL_POWER GND
J 1
(-6300 2775);
DISPLAY 0.872340 (-6300 2775);
PAINT GREEN (-6300 2775);
DISPLAY INVISIBLE (-6300 2775);
FORCEPROP 1 LAST PATH I77
J 0
(-6250 2850);
DISPLAY 0.872340 (-6250 2850);
PAINT AQUA (-6250 2850);
DISPLAY INVISIBLE (-6250 2850);
FORCEADD OFFPAGE..4
R 2
(-6600 3325);
FORCEPROP 2 LAST $XR0 139 
J 0
(-6852 3325);
DISPLAY 0.638298 (-6852 3325);
PAINT MONO (-6852 3325);
FORCEPROP 2 LAST CDS_LIB standard
J 0
(-6600 3325);
DISPLAY INVISIBLE (-6600 3325);
FORCEPROP 1 LAST COMMENT_BODY TRUE
J 2
(-6575 3225);
DISPLAY 0.872340 (-6575 3225);
PAINT GREEN (-6575 3225);
DISPLAY INVISIBLE (-6575 3225);
FORCEPROP 1 LAST OFFPAGE TRUE
J 2
(-6925 3200);
DISPLAY 0.872340 (-6925 3200);
PAINT GREEN (-6925 3200);
DISPLAY INVISIBLE (-6925 3200);
FORCEPROP 2 LAST PATH I78
J 0
(-6875 3375);
DISPLAY 1.021277 (-6875 3375);
DISPLAY INVISIBLE (-6875 3375);
FORCEADD Q_RES..1
(525 4050);
FORCEPROP 1 LAST PART_NUMBER CS00002JB13
J 0
(400 4000);
DISPLAY 0.638298 (400 4000);
DISPLAY INVISIBLE (400 4000);
FORCEPROP 1 LAST PACK_TYPE 0402LF
J 0
(50 4050);
DISPLAY 0.638298 (50 4050);
FORCEPROP 1 LAST TOLERANCE 5%
J 0
(750 4050);
DISPLAY 0.638298 (750 4050);
FORCEPROP 1 LAST MATERIAL EMPTY
J 0
(825 4050);
DISPLAY 0.638298 (825 4050);
PAINT RED (825 4050);
FORCEPROP 1 LAST WATTAGE 1/16W
J 2
(1125 4050);
DISPLAY 0.638298 (1125 4050);
FORCEPROP 1 LAST VALUE 0
J 2
(725 4050);
DISPLAY 0.638298 (725 4050);
FORCEPROP 1 LAST $LOCATION R3440
J 0
(325 4050);
DISPLAY 0.638298 (325 4050);
FORCEPROP 1 LASTPIN (425 4050) $PN 1
J 0
(437 4062);
DISPLAY 0.787234 (437 4062);
PAINT MONO (437 4062);
FORCEPROP 1 LASTPIN (625 4050) $PN 2
J 0
(587 4062);
DISPLAY 0.787234 (587 4062);
PAINT MONO (587 4062);
FORCEPROP 2 LAST CDS_LIB pure_quanta
J 0
(525 4050);
DISPLAY INVISIBLE (525 4050);
FORCEPROP 1 LAST PATH I8
J 0
(475 4200);
DISPLAY 0.978723 (475 4200);
PAINT WHITE (475 4200);
DISPLAY INVISIBLE (475 4200);
FORCEPROP 0 LAST CDS_LOCATION R3440
J 0
(1125 4100);
DISPLAY 1.021277 (1125 4100);
DISPLAY INVISIBLE (1125 4100);
FORCEPROP 0 LAST $SEC 1
J 0
(1125 4100);
DISPLAY 0.680851 (1125 4100);
PAINT MONO (1125 4100);
DISPLAY INVISIBLE (1125 4100);
FORCEPROP 0 LAST CDS_SEC 1
J 0
(1125 4100);
DISPLAY 1.021277 (1125 4100);
DISPLAY INVISIBLE (1125 4100);
FORCEADD OFFPAGE..2
R 2
(-675 4275);
FORCEPROP 2 LAST $XR1 143 
J 0
(-1050 4275);
DISPLAY 0.638298 (-1050 4275);
PAINT MONO (-1050 4275);
FORCEPROP 2 LAST $XR0 145 
J 0
(-930 4275);
DISPLAY 0.638298 (-930 4275);
PAINT MONO (-930 4275);
FORCEPROP 1 LAST OFFPAGE TRUE
J 2
(-1000 4150);
DISPLAY 0.872340 (-1000 4150);
PAINT AQUA (-1000 4150);
DISPLAY INVISIBLE (-1000 4150);
FORCEPROP 1 LAST COMMENT_BODY TRUE
J 2
(-630 4180);
DISPLAY 0.872340 (-630 4180);
PAINT GREEN (-630 4180);
DISPLAY INVISIBLE (-630 4180);
FORCEPROP 2 LAST CDS_LIB standard
J 0
(-675 4275);
DISPLAY INVISIBLE (-675 4275);
FORCEPROP 2 LAST PATH I9
J 0
(-925 4325);
DISPLAY 1.021277 (-925 4325);
DISPLAY INVISIBLE (-925 4325);
FORCEADD QUANTA_TITLE_BLOCK_C..1
(1850 2625);
FORCEPROP 0 LAST CDS_CON_LAST_MODIFIED Fri Aug 25 14:02:05 2023
J 0
(-35 2640);
DISPLAY INVISIBLE (-35 2640);
FORCEPROP 1 LAST CUSTOM_TXT_CDS <CON_LAST_MODIFIED>
J 0
(-35 2640);
DISPLAY 0.978723 (-35 2640);
FORCEPROP 2 LAST CUSTOM_TXT_CDS <XR_PAGE_TITLE>
J 0
(-6040 7875);
DISPLAY 0.638298 (-6040 7875);
PAINT PINK (-6040 7875);
DISPLAY INVISIBLE (-6040 7875);
FORCEPROP 1 LAST CUSTOM_TXT_CDS <NAME_2>
J 0
(-1325 2675);
FORCEPROP 1 LAST CUSTOM_TXT_CDS <NAME_1>
J 0
(-1325 2800);
FORCEPROP 1 LAST CUSTOM_TXT_CDS <Q_NUMBER>
J 0
(447 2728);
DISPLAY 1.212766 (447 2728);
FORCEPROP 1 LAST CUSTOM_TXT_CDS <Q_PROJ>
J 0
(-532 2727);
DISPLAY 1.212766 (-532 2727);
FORCEPROP 1 LAST CUSTOM_TXT_CDS <Q_REV>
J 0
(1666 2728);
DISPLAY 1.212766 (1666 2728);
FORCEPROP 1 LAST CUSTOM_TXT_CDS <CON_PAGE_NUM> OF <CON_TOTAL_PAGES>
J 0
(1404 2643);
DISPLAY 0.978723 (1404 2643);
FORCEPROP 1 LAST Q_TITLE EXAMAX_PRESENT
J 0
(-7516 2651);
DISPLAY 2.446809 (-7516 2651);
PAINT GREEN (-7516 2651);
FORCEPROP 1 LAST Q_DEPT 
J 1
(-1913 2674);
DISPLAY 1.957447 (-1913 2674);
PAINT GREEN (-1913 2674);
FORCEPROP 2 LAST CDS_XR_PAGE_TITLE CR-144 : @S9S_MB_2U_LIB.S9S_MB_2U(SCH_1):PAGE144
J 0
(-6040 7875);
DISPLAY 0.638298 (-6040 7875);
PAINT PINK (-6040 7875);
DISPLAY INVISIBLE (-6040 7875);
FORCEPROP 2 LAST CDS_LIB pure_quanta
J 0
(1850 2625);
DISPLAY INVISIBLE (1850 2625);
FORCEPROP 1 LAST CDS_LMAN_SYM_OUTLINE -9475,6775,100,-125
J 0
(1850 2625);
DISPLAY 0.468085 (1850 2625);
PAINT GREEN (1850 2625);
DISPLAY INVISIBLE (1850 2625);
FORCEPROP 1 LAST COMMENT_BODY TRUE
J 0
(1862 2612);
DISPLAY 0.978723 (1862 2612);
PAINT GREEN (1862 2612);
DISPLAY INVISIBLE (1862 2612);
FORCEPROP 2 LAST PAGE_BORDER TRUE
J 0
(-6040 7875);
DISPLAY 0.638298 (-6040 7875);
PAINT PINK (-6040 7875);
DISPLAY INVISIBLE (-6040 7875);
FORCEADD DNS..2
(-3250 3600);
PAINT RED (-3250 3600);
FORCEPROP 2 LAST CDS_LIB mstr_misc
J 0
(-3250 3600);
DISPLAY INVISIBLE (-3250 3600);
FORCEPROP 1 LAST COMMENT_BODY TRUE
J 0
(-3250 3600);
DISPLAY INVISIBLE (-3250 3600);
FORCEADD DNS..2
(-6325 3100);
PAINT RED (-6325 3100);
FORCEPROP 2 LAST CDS_LIB mstr_misc
J 0
(-6325 3100);
DISPLAY INVISIBLE (-6325 3100);
FORCEPROP 1 LAST COMMENT_BODY TRUE
J 0
(-6325 3100);
DISPLAY INVISIBLE (-6325 3100);
FORCEADD DNS..2
(-6350 4500);
PAINT RED (-6350 4500);
FORCEPROP 1 LAST COMMENT_BODY TRUE
J 0
(-6350 4500);
DISPLAY INVISIBLE (-6350 4500);
FORCEPROP 2 LAST CDS_LIB mstr_misc
J 0
(-6350 4500);
DISPLAY INVISIBLE (-6350 4500);
FORCEADD DNS..2
(-3275 5000);
PAINT RED (-3275 5000);
FORCEPROP 1 LAST COMMENT_BODY TRUE
J 0
(-3275 5000);
DISPLAY INVISIBLE (-3275 5000);
FORCEPROP 2 LAST CDS_LIB mstr_misc
J 0
(-3275 5000);
DISPLAY INVISIBLE (-3275 5000);
FORCEADD DNS..2
(550 4300);
PAINT RED (550 4300);
FORCEPROP 1 LAST COMMENT_BODY TRUE
J 0
(550 4300);
DISPLAY INVISIBLE (550 4300);
FORCEPROP 2 LAST CDS_LIB mstr_misc
J 0
(550 4300);
DISPLAY INVISIBLE (550 4300);
FORCEADD DNS..2
(550 4050);
PAINT RED (550 4050);
FORCEPROP 2 LAST CDS_LIB mstr_misc
J 0
(550 4050);
DISPLAY INVISIBLE (550 4050);
FORCEPROP 1 LAST COMMENT_BODY TRUE
J 0
(550 4050);
DISPLAY INVISIBLE (550 4050);
FORCEADD DNS..2
(-6700 7675);
PAINT RED (-6700 7675);
FORCEPROP 1 LAST COMMENT_BODY TRUE
J 0
(-6700 7675);
DISPLAY INVISIBLE (-6700 7675);
FORCEPROP 2 LAST CDS_LIB mstr_misc
J 0
(-6700 7675);
DISPLAY INVISIBLE (-6700 7675);
FORCEADD DNS..2
(-3625 8175);
PAINT RED (-3625 8175);
FORCEPROP 1 LAST COMMENT_BODY TRUE
J 0
(-3625 8175);
DISPLAY INVISIBLE (-3625 8175);
FORCEPROP 2 LAST CDS_LIB mstr_misc
J 0
(-3625 8175);
DISPLAY INVISIBLE (-3625 8175);
FORCEADD DNS..2
(-3500 6650);
PAINT RED (-3500 6650);
FORCEPROP 1 LAST COMMENT_BODY TRUE
J 0
(-3500 6650);
DISPLAY INVISIBLE (-3500 6650);
FORCEPROP 2 LAST CDS_LIB mstr_misc
J 0
(-3500 6650);
DISPLAY INVISIBLE (-3500 6650);
FORCEADD DNS..2
(-6575 6150);
PAINT RED (-6575 6150);
FORCEPROP 1 LAST COMMENT_BODY TRUE
J 0
(-6575 6150);
DISPLAY INVISIBLE (-6575 6150);
FORCEPROP 2 LAST CDS_LIB mstr_misc
J 0
(-6575 6150);
DISPLAY INVISIBLE (-6575 6150);
WIRE 16 -1 (-6375 5200)(-6375 5100);
WIRE 16 -1 (-5200 5550)(-5200 5475);
WIRE 16 -1 (-4050 5675)(-4050 5600);
WIRE 16 -1 (-6350 3800)(-6350 3700);
WIRE 16 -1 (-4025 4275)(-4025 4200);
WIRE 16 -1 (-5175 4150)(-5175 4075);
WIRE 16 -1 (-6725 8375)(-6725 8275);
WIRE 16 -1 (-5550 8725)(-5550 8650);
WIRE 16 -1 (-4400 8850)(-4400 8775);
WIRE 16 -1 (-4275 7325)(-4275 7250);
WIRE 16 -1 (-5425 7200)(-5425 7125);
WIRE 16 -1 (-6600 6850)(-6600 6750);
WIRE 16 -1 (-3250 3525)(-3250 3475);
WIRE 16 -1 (-4025 3475)(-4025 3350);
WIRE 16 -1 (-5175 3175)(-5175 3050);
WIRE 16 -1 (-6325 3025)(-6325 2900);
WIRE 16 -1 (-6350 4425)(-6350 4300);
WIRE 16 -1 (-6575 6075)(-6575 5950);
WIRE 16 -1 (-5200 4575)(-5200 4450);
WIRE 16 -1 (-4050 4875)(-4050 4750);
WIRE 16 -1 (-3275 4925)(-3275 4875);
WIRE 16 -1 (1575 3075)(1575 3450);
WIRE 16 -1 (-6700 7600)(-6700 7475);
WIRE 16 -1 (-5550 7750)(-5550 7625);
WIRE 16 -1 (-4400 8050)(-4400 7925);
WIRE 16 -1 (-3625 8100)(-3625 8050);
WIRE 16 -1 (-3500 6575)(-3500 6525);
WIRE 16 -1 (-4275 6525)(-4275 6400);
WIRE 16 -1 (-5425 6225)(-5425 6100);
WIRE 16 -1 (-6350 3325)(-6550 3325);
WIRE 16 -1 (-6350 3500)(-6350 3325);
WIRE 16 -1 (-6325 3325)(-6350 3325);
WIRE 16 -1 (-5425 3325)(-6325 3325);
FORCEPROP 2 LAST SIG_NAME PRSNT_CABLE_GPU_A3_N
J 0
(-6285 3335);
DISPLAY 0.808511 (-6285 3335);
WIRE 16 -1 (-6325 3225)(-6325 3325);
WIRE 16 -1 (-4025 3925)(-4025 3875);
WIRE 16 -1 (-4025 4000)(-4025 3925);
WIRE 16 -1 (-3250 3925)(-4025 3925);
FORCEPROP 2 LAST SIG_NAME PRSNT_CABLE_GPU_A3_ISO_N
J 0
(-3960 3935);
DISPLAY 0.808511 (-3960 3935);
WIRE 16 -1 (-3250 3725)(-3250 3925);
WIRE 16 -1 (-2950 3925)(-3250 3925);
WIRE 16 -1 (-5175 3575)(-5175 3625);
WIRE 16 -1 (-4275 3625)(-5175 3625);
FORCEPROP 2 LAST SIG_NAME PRSNT_CABLE_GPU_A3
J 0
(-5110 3635);
DISPLAY 0.808511 (-5110 3635);
WIRE 16 -1 (-5175 3875)(-5175 3625);
WIRE 16 -1 (-4050 5325)(-4050 5275);
WIRE 16 -1 (-4050 5400)(-4050 5325);
WIRE 16 -1 (-3275 5325)(-4050 5325);
FORCEPROP 2 LAST SIG_NAME PRSNT_CABLE_SWB_B1_ISO_N
J 0
(-3985 5335);
DISPLAY 0.808511 (-3985 5335);
WIRE 16 -1 (-3275 5125)(-3275 5325);
WIRE 16 -1 (-2975 5325)(-3275 5325);
WIRE 16 -1 (-5200 4975)(-5200 5025);
WIRE 16 -1 (-4300 5025)(-5200 5025);
FORCEPROP 2 LAST SIG_NAME PRSNT_CABLE_SWB_B1
J 0
(-5135 5035);
DISPLAY 0.808511 (-5135 5035);
WIRE 16 -1 (-5200 5275)(-5200 5025);
WIRE 16 -1 (-6375 4725)(-6575 4725);
WIRE 16 -1 (-6375 4900)(-6375 4725);
WIRE 16 -1 (-6350 4725)(-6375 4725);
WIRE 16 -1 (-5450 4725)(-6350 4725);
FORCEPROP 2 LAST SIG_NAME PRSNT_CABLE_SWB_B1_N
J 0
(-6310 4735);
DISPLAY 0.808511 (-6310 4735);
WIRE 16 -1 (-6350 4625)(-6350 4725);
WIRE 16 -1 (450 4275)(-625 4275);
FORCEPROP 2 LAST SIG_NAME HGX_DETECT_N_ISO
J 0
(-585 4285);
DISPLAY 0.638298 (-585 4285);
WIRE 16 -1 (425 4050)(-625 4050);
FORCEPROP 2 LAST SIG_NAME GPU_BASE_ID0
J 0
(-585 4060);
DISPLAY 0.638298 (-585 4060);
WIRE 16 -1 (425 3850)(-625 3850);
FORCEPROP 2 LAST SIG_NAME GPU_BASE_ID1
J 0
(-585 3860);
DISPLAY 0.638298 (-585 3860);
WIRE 16 -1 (425 3650)(-625 3650);
FORCEPROP 2 LAST SIG_NAME GPU_PEX_STRAP0
J 0
(-585 3660);
DISPLAY 0.638298 (-585 3660);
WIRE 16 -1 (425 3450)(-625 3450);
FORCEPROP 2 LAST SIG_NAME GPU_PEX_STRAP1
J 0
(-585 3460);
DISPLAY 0.638298 (-585 3460);
WIRE 16 2175 (275 3725)(1200 3725);
WIRE 16 2175 (1200 3725)(1200 3325);
WIRE 16 2175 (275 3725)(275 3325);
WIRE 16 2175 (275 3325)(1200 3325);
WIRE 16 -1 (-3625 8300)(-3625 8500);
WIRE 16 -1 (-3325 8500)(-3625 8500);
WIRE 16 -1 (-4400 8500)(-4400 8450);
WIRE 16 -1 (-3625 8500)(-4400 8500);
FORCEPROP 2 LAST SIG_NAME PRSNT_SWB_ISO_N
J 0
(-4335 8510);
DISPLAY 0.808511 (-4335 8510);
WIRE 16 -1 (-4400 8575)(-4400 8500);
WIRE 16 -1 (-5550 8150)(-5550 8200);
WIRE 16 -1 (-4650 8200)(-5550 8200);
FORCEPROP 2 LAST SIG_NAME PRSNT_SWB
J 0
(-5485 8210);
DISPLAY 0.808511 (-5485 8210);
WIRE 16 -1 (-5550 8450)(-5550 8200);
WIRE 16 -1 (-6725 7900)(-6925 7900);
WIRE 16 -1 (-6725 8075)(-6725 7900);
WIRE 16 -1 (-6700 7900)(-6725 7900);
WIRE 16 -1 (-5800 7900)(-6700 7900);
FORCEPROP 2 LAST SIG_NAME PRSNT_SWB_N
J 0
(-6660 7910);
DISPLAY 0.808511 (-6660 7910);
WIRE 16 -1 (-6700 7800)(-6700 7900);
WIRE 16 -1 (-4275 6975)(-4275 6925);
WIRE 16 -1 (-4275 7050)(-4275 6975);
WIRE 16 -1 (-3500 6975)(-4275 6975);
FORCEPROP 2 LAST SIG_NAME PRSNT_CABLE_SWB_B2_ISO_N
J 0
(-4210 6985);
DISPLAY 0.808511 (-4210 6985);
WIRE 16 -1 (-3500 6775)(-3500 6975);
WIRE 16 -1 (-3200 6975)(-3500 6975);
WIRE 16 -1 (-6600 6375)(-6800 6375);
WIRE 16 -1 (-6600 6550)(-6600 6375);
WIRE 16 -1 (-6575 6375)(-6600 6375);
WIRE 16 -1 (-5675 6375)(-6575 6375);
FORCEPROP 2 LAST SIG_NAME PRSNT_CABLE_SWB_B2_N
J 0
(-6535 6385);
DISPLAY 0.808511 (-6535 6385);
WIRE 16 -1 (-6575 6275)(-6575 6375);
WIRE 16 -1 (1575 4275)(650 4275);
WIRE 16 -1 (1575 4050)(625 4050);
WIRE 16 -1 (1575 4050)(1575 4275);
WIRE 16 -1 (1575 3850)(625 3850);
WIRE 16 -1 (1575 3850)(1575 4050);
WIRE 16 -1 (1575 3650)(625 3650);
WIRE 16 -1 (1575 3650)(1575 3850);
WIRE 16 -1 (1575 3450)(625 3450);
WIRE 16 -1 (1575 3450)(1575 3650);
WIRE 16 -1 (-5425 6625)(-5425 6675);
WIRE 16 -1 (-4525 6675)(-5425 6675);
FORCEPROP 2 LAST SIG_NAME PRSNT_CABLE_SWB_B2
J 0
(-5360 6685);
DISPLAY 0.808511 (-5360 6685);
WIRE 16 -1 (-5425 6925)(-5425 6675);
DOT 1 (1575 4050);
DOT 1 (1575 3650);
DOT 1 (1575 3850);
DOT 1 (1575 3450);
DOT 1 (-3625 8500);
DOT 1 (-4400 8500);
DOT 1 (-5550 8200);
DOT 1 (-6725 7900);
DOT 1 (-6700 7900);
DOT 1 (-6600 6375);
DOT 1 (-6575 6375);
DOT 1 (-5425 6675);
DOT 1 (-4275 6975);
DOT 1 (-3500 6975);
DOT 1 (-3250 3925);
DOT 1 (-4025 3925);
DOT 1 (-5175 3625);
DOT 1 (-6375 4725);
DOT 1 (-6350 4725);
DOT 1 (-5200 5025);
DOT 1 (-4050 5325);
DOT 1 (-3275 5325);
DOT 1 (-6350 3325);
DOT 1 (-6325 3325);
FORCENOTE
20210527 MODIFY FOR GT
(-2425 8950) 0;
DISPLAY LEFT (-2425 8950);
DISPLAY 2.510638 (-2425 8950);
PAINT PINK (-2425 8950);
FORCENOTE
20220504 POP R3442,R3443
(150 3225) 0;
DISPLAY LEFT (150 3225);
DISPLAY 1.063830 (150 3225);
PAINT WHITE (150 3225);
QUIT
